G04 ================== begin FILE IDENTIFICATION RECORD ==================*
G04 Layout Name:  DA0T6MTH8C0_t6m_tray_bp_c_brd_103112_274.brd*
G04 Film Name:    gnd*
G04 File Format:  Gerber RS274X*
G04 File Origin:  Cadence Allegro 16.3-S048*
G04 Origin Date:  Tue Nov 26 11:26:41 2013*
G04 *
G04 Layer:  DRAWING FORMAT/TITLE_BLOCK*
G04 Layer:  VIA CLASS/GND*
G04 Layer:  PIN/GND*
G04 Layer:  MANUFACTURING/PHOTOPLOT_OUTLINE*
G04 Layer:  ETCH/GND*
G04 Layer:  DRAWING FORMAT/TITLE_DATA_GND*
G04 *
G04 Offset:    (0.00 0.00)*
G04 Mirror:    No*
G04 Mode:      Negative*
G04 Rotation:  0*
G04 FullContactRelief:  No*
G04 UndefLineWidth:     6.00*
G04 ================== end FILE IDENTIFICATION RECORD ====================*
%FSLAX25Y25*MOIN*%
%IR0*IPPOS*OFA0.00000B0.00000*MIA0B0*SFA1.00000B1.00000*%
%ADD18C,.03*%
%ADD17C,.04*%
%ADD28C,.05*%
%ADD19C,.072*%
%ADD15C,.063*%
%ADD34C,.055*%
%AMMACRO33*
4,1,36,0.0,.0155,
-.002692,.015265,
-.005301,.014565,
-.00775,.013423,
-.009963,.011874,
-.011874,.009963,
-.013423,.00775,
-.014565,.005301,
-.015265,.002692,
-.0155,0.0,
-.015265,-.002692,
-.014565,-.005301,
-.013423,-.00775,
-.011874,-.009963,
-.009963,-.011874,
-.00775,-.013423,
-.005301,-.014565,
-.002692,-.015265,
0.0,-.0155,
.002692,-.015265,
.005301,-.014565,
.00775,-.013423,
.009963,-.011874,
.011874,-.009963,
.013423,-.00775,
.014565,-.005301,
.015265,-.002692,
.0155,0.0,
.015265,.002692,
.014565,.005301,
.013423,.00775,
.011874,.009963,
.009963,.011874,
.00775,.013423,
.005301,.014565,
.002692,.015265,
0.0,.0155,
0.0*
%
%ADD33MACRO33*%
%ADD14C,.073*%
%ADD30C,.093*%
%ADD11C,.066*%
%AMMACRO37*
4,1,36,0.0,.004,
.000695,.003939,
.001368,.003759,
.002,.003464,
.002571,.003064,
.003064,.002571,
.003464,.002,
.003759,.001368,
.003939,.000695,
.004,0.0,
.003939,-.000695,
.003759,-.001368,
.003464,-.002,
.003064,-.002571,
.002571,-.003064,
.002,-.003464,
.001368,-.003759,
.000695,-.003939,
0.0,-.004,
-.000695,-.003939,
-.001368,-.003759,
-.002,-.003464,
-.002571,-.003064,
-.003064,-.002571,
-.003464,-.002,
-.003759,-.001368,
-.003939,-.000695,
-.004,0.0,
-.003939,.000695,
-.003759,.001368,
-.003464,.002,
-.003064,.002571,
-.002571,.003064,
-.002,.003464,
-.001368,.003759,
-.000695,.003939,
0.0,.004,
180.*
%
%ADD37MACRO37*%
%AMMACRO24*
4,1,36,0.0,.004,
.000695,.003939,
.001368,.003759,
.002,.003464,
.002571,.003064,
.003064,.002571,
.003464,.002,
.003759,.001368,
.003939,.000695,
.004,0.0,
.003939,-.000695,
.003759,-.001368,
.003464,-.002,
.003064,-.002571,
.002571,-.003064,
.002,-.003464,
.001368,-.003759,
.000695,-.003939,
0.0,-.004,
-.000695,-.003939,
-.001368,-.003759,
-.002,-.003464,
-.002571,-.003064,
-.003064,-.002571,
-.003464,-.002,
-.003759,-.001368,
-.003939,-.000695,
-.004,0.0,
-.003939,.000695,
-.003759,.001368,
-.003464,.002,
-.003064,.002571,
-.002571,.003064,
-.002,.003464,
-.001368,.003759,
-.000695,.003939,
0.0,.004,
270.*
%
%ADD24MACRO24*%
%ADD20C,.058*%
%AMMACRO29*
4,1,36,0.0,.0175,
-.003039,.017234,
-.005985,.016445,
-.00875,.015155,
-.011249,.013406,
-.013406,.011249,
-.015155,.00875,
-.016445,.005985,
-.017234,.003039,
-.0175,0.0,
-.017234,-.003039,
-.016445,-.005985,
-.015155,-.00875,
-.013406,-.011249,
-.011249,-.013406,
-.00875,-.015155,
-.005985,-.016445,
-.003039,-.017234,
0.0,-.0175,
.003039,-.017234,
.005985,-.016445,
.00875,-.015155,
.011249,-.013406,
.013406,-.011249,
.015155,-.00875,
.016445,-.005985,
.017234,-.003039,
.0175,0.0,
.017234,.003039,
.016445,.005985,
.015155,.00875,
.013406,.011249,
.011249,.013406,
.00875,.015155,
.005985,.016445,
.003039,.017234,
0.0,.0175,
0.0*
%
%ADD29MACRO29*%
%AMMACRO22*
4,1,36,0.0,.009,
.001563,.008863,
.003078,.008457,
.0045,.007794,
.005785,.006894,
.006894,.005785,
.007794,.0045,
.008457,.003078,
.008863,.001563,
.009,0.0,
.008863,-.001563,
.008457,-.003078,
.007794,-.0045,
.006894,-.005785,
.005785,-.006894,
.0045,-.007794,
.003078,-.008457,
.001563,-.008863,
0.0,-.009,
-.001563,-.008863,
-.003078,-.008457,
-.0045,-.007794,
-.005785,-.006894,
-.006894,-.005785,
-.007794,-.0045,
-.008457,-.003078,
-.008863,-.001563,
-.009,0.0,
-.008863,.001563,
-.008457,.003078,
-.007794,.0045,
-.006894,.005785,
-.005785,.006894,
-.0045,.007794,
-.003078,.008457,
-.001563,.008863,
0.0,.009,
0.0*
%
%ADD22MACRO22*%
%AMMACRO26*
4,1,36,0.0,.014,
-.002431,.013787,
-.004788,.013156,
-.007,.012124,
-.008999,.010725,
-.010725,.008999,
-.012124,.007,
-.013156,.004788,
-.013787,.002431,
-.014,0.0,
-.013787,-.002431,
-.013156,-.004788,
-.012124,-.007,
-.010725,-.008999,
-.008999,-.010725,
-.007,-.012124,
-.004788,-.013156,
-.002431,-.013787,
0.0,-.014,
.002431,-.013787,
.004788,-.013156,
.007,-.012124,
.008999,-.010725,
.010725,-.008999,
.012124,-.007,
.013156,-.004788,
.013787,-.002431,
.014,0.0,
.013787,.002431,
.013156,.004788,
.012124,.007,
.010725,.008999,
.008999,.010725,
.007,.012124,
.004788,.013156,
.002431,.013787,
0.0,.014,
0.0*
%
%ADD26MACRO26*%
%AMMACRO35*
4,1,15,.04161,.02393,
.045133,.016341,
.047285,.008255,
.048,-.000081,
.047257,-.008415,
.045078,-.016493,
.04161,-.02393,
.04671,-.02903,
.051041,-.020478,
.053822,-.011304,
.054967,-.001786,
.054442,.007786,
.052263,.017122,
.048496,.025937,
.04671,.02903,
.04161,.02393,
180.*
4,1,15,.02393,-.04161,
.016341,-.045133,
.008255,-.047285,
-.000081,-.048,
-.008415,-.047257,
-.016493,-.045078,
-.02393,-.04161,
-.02903,-.04671,
-.020478,-.051041,
-.011304,-.053822,
-.001786,-.054967,
.007786,-.054442,
.017122,-.052263,
.025937,-.048496,
.02903,-.04671,
.02393,-.04161,
180.*
4,1,15,-.04161,-.02393,
-.045133,-.016341,
-.047285,-.008255,
-.048,.000081,
-.047257,.008415,
-.045078,.016493,
-.04161,.02393,
-.04671,.02903,
-.051041,.020478,
-.053822,.011304,
-.054967,.001786,
-.054442,-.007786,
-.052263,-.017122,
-.048496,-.025937,
-.04671,-.02903,
-.04161,-.02393,
180.*
4,1,15,-.02393,.04161,
-.016341,.045133,
-.008255,.047285,
.000081,.048,
.008415,.047257,
.016493,.045078,
.02393,.04161,
.02903,.04671,
.020478,.051041,
.011304,.053822,
.001786,.054967,
-.007786,.054442,
-.017122,.052263,
-.025937,.048496,
-.02903,.04671,
-.02393,.04161,
180.*
%
%ADD35MACRO35*%
%AMMACRO31*
4,1,36,0.0,.0195,
-.003386,.019204,
-.006669,.018324,
-.00975,.016887,
-.012534,.014938,
-.014938,.012534,
-.016887,.00975,
-.018324,.006669,
-.019204,.003386,
-.0195,0.0,
-.019204,-.003386,
-.018324,-.006669,
-.016887,-.00975,
-.014938,-.012534,
-.012534,-.014938,
-.00975,-.016887,
-.006669,-.018324,
-.003386,-.019204,
0.0,-.0195,
.003386,-.019204,
.006669,-.018324,
.00975,-.016887,
.012534,-.014938,
.014938,-.012534,
.016887,-.00975,
.018324,-.006669,
.019204,-.003386,
.0195,0.0,
.019204,.003386,
.018324,.006669,
.016887,.00975,
.014938,.012534,
.012534,.014938,
.00975,.016887,
.006669,.018324,
.003386,.019204,
0.0,.0195,
0.0*
%
%ADD31MACRO31*%
%AMMACRO38*
4,1,16,.04853,.03085,
.05315,.021954,
.056155,.012391,
.057453,.002452,
.057006,-.007562,
.054827,-.017346,
.050982,-.026603,
.04853,-.03085,
.05358,-.0359,
.059,-.026051,
.062627,-.01541,
.064352,-.0043,
.064121,.00694,
.061942,.017969,
.05788,.028452,
.05358,.0359,
.04853,.03085,
0.0*
4,1,16,.03085,-.04853,
.021954,-.05315,
.012391,-.056155,
.002452,-.057453,
-.007562,-.057006,
-.017346,-.054827,
-.026603,-.050982,
-.03085,-.04853,
-.0359,-.05358,
-.026051,-.059,
-.01541,-.062627,
-.0043,-.064352,
.00694,-.064121,
.017969,-.061942,
.028452,-.05788,
.0359,-.05358,
.03085,-.04853,
0.0*
4,1,16,-.04853,-.03085,
-.05315,-.021954,
-.056155,-.012391,
-.057453,-.002452,
-.057006,.007562,
-.054827,.017346,
-.050982,.026603,
-.04853,.03085,
-.05358,.0359,
-.059,.026051,
-.062627,.01541,
-.064352,.0043,
-.064121,-.00694,
-.061942,-.017969,
-.05788,-.028452,
-.05358,-.0359,
-.04853,-.03085,
0.0*
4,1,16,-.03085,.04853,
-.021954,.05315,
-.012391,.056155,
-.002452,.057453,
.007562,.057006,
.017346,.054827,
.026603,.050982,
.03085,.04853,
.0359,.05358,
.026051,.059,
.01541,.062627,
.0043,.064352,
-.00694,.064121,
-.017969,.061942,
-.028452,.05788,
-.0359,.05358,
-.03085,.04853,
0.0*
%
%ADD38MACRO38*%
%AMMACRO25*
4,1,16,.07401,.04573,
.080827,.032184,
.085187,.017659,
.08696,.002598,
.08609,-.012541,
.082604,-.0273,
.076608,-.04123,
.07401,-.04573,
.07909,-.0508,
.08671,-.036294,
.091695,-.020686,
.093894,-.004449,
.09324,.011923,
.089753,.027933,
.083539,.043094,
.07909,.0508,
.07401,.04573,
0.0*
4,1,16,.04573,-.07401,
.032184,-.080827,
.017659,-.085187,
.002598,-.08696,
-.012541,-.08609,
-.0273,-.082604,
-.04123,-.076608,
-.04573,-.07401,
-.0508,-.07909,
-.036294,-.08671,
-.020686,-.091695,
-.004449,-.093894,
.011923,-.09324,
.027933,-.089753,
.043094,-.083539,
.0508,-.07909,
.04573,-.07401,
0.0*
4,1,16,-.07401,-.04573,
-.080827,-.032184,
-.085187,-.017659,
-.08696,-.002598,
-.08609,.012541,
-.082604,.0273,
-.076608,.04123,
-.07401,.04573,
-.07909,.0508,
-.08671,.036294,
-.091695,.020686,
-.093894,.004449,
-.09324,-.011923,
-.089753,-.027933,
-.083539,-.043094,
-.07909,-.0508,
-.07401,-.04573,
0.0*
4,1,16,-.04573,.07401,
-.032184,.080827,
-.017659,.085187,
-.002598,.08696,
.012541,.08609,
.0273,.082604,
.04123,.076608,
.04573,.07401,
.0508,.07909,
.036294,.08671,
.020686,.091695,
.004449,.093894,
-.011923,.09324,
-.027933,.089753,
-.043094,.083539,
-.0508,.07909,
-.04573,.07401,
0.0*
%
%ADD25MACRO25*%
%AMMACRO21*
4,1,15,.02364,.01304,
.025545,.008737,
.026674,.004168,
.026993,-.000527,
.026491,-.005206,
.025185,-.009727,
.02364,-.01304,
.02875,-.01815,
.031465,-.012882,
.033224,-.007222,
.033973,-.001343,
.03369,.004576,
.032384,.010357,
.030093,.015823,
.02875,.01815,
.02364,.01304,
90.*
4,1,15,.01304,-.02364,
.008737,-.025545,
.004168,-.026674,
-.000527,-.026993,
-.005206,-.026491,
-.009727,-.025185,
-.01304,-.02364,
-.01815,-.02875,
-.012882,-.031465,
-.007222,-.033224,
-.001343,-.033973,
.004576,-.03369,
.010357,-.032384,
.015823,-.030093,
.01815,-.02875,
.01304,-.02364,
90.*
4,1,15,-.02364,-.01304,
-.025545,-.008737,
-.026674,-.004168,
-.026993,.000527,
-.026491,.005206,
-.025185,.009727,
-.02364,.01304,
-.02875,.01815,
-.031465,.012882,
-.033224,.007222,
-.033973,.001343,
-.03369,-.004576,
-.032384,-.010357,
-.030093,-.015823,
-.02875,-.01815,
-.02364,-.01304,
90.*
4,1,15,-.01304,.02364,
-.008737,.025545,
-.004168,.026674,
.000527,.026993,
.005206,.026491,
.009727,.025185,
.01304,.02364,
.01815,.02875,
.012882,.031465,
.007222,.033224,
.001343,.033973,
-.004576,.03369,
-.010357,.032384,
-.015823,.030093,
-.01815,.02875,
-.01304,.02364,
90.*
%
%ADD21MACRO21*%
%AMMACRO16*
4,1,16,.02548,.01487,
.027675,.01022,
.029029,.005259,
.029501,.000138,
.029077,-.004987,
.027769,-.009961,
.025618,-.014631,
.02548,-.01487,
.03056,-.01996,
.033562,-.01435,
.035544,-.008304,
.036446,-.002006,
.03624,.004353,
.034934,.01058,
.032566,.016486,
.03056,.01996,
.02548,.01487,
90.*
4,1,16,.01487,-.02548,
.01022,-.027675,
.005259,-.029029,
.000138,-.029501,
-.004987,-.029077,
-.009961,-.027769,
-.014631,-.025618,
-.01487,-.02548,
-.01996,-.03056,
-.01435,-.033562,
-.008304,-.035544,
-.002006,-.036446,
.004353,-.03624,
.01058,-.034934,
.016486,-.032566,
.01996,-.03056,
.01487,-.02548,
90.*
4,1,16,-.02548,-.01487,
-.027675,-.01022,
-.029029,-.005259,
-.029501,-.000138,
-.029077,.004987,
-.027769,.009961,
-.025618,.014631,
-.02548,.01487,
-.03056,.01996,
-.033562,.01435,
-.035544,.008304,
-.036446,.002006,
-.03624,-.004353,
-.034934,-.01058,
-.032566,-.016486,
-.03056,-.01996,
-.02548,-.01487,
90.*
4,1,16,-.01487,.02548,
-.01022,.027675,
-.005259,.029029,
-.000138,.029501,
.004987,.029077,
.009961,.027769,
.014631,.025618,
.01487,.02548,
.01996,.03056,
.01435,.033562,
.008304,.035544,
.002006,.036446,
-.004353,.03624,
-.01058,.034934,
-.016486,.032566,
-.01996,.03056,
-.01487,.02548,
90.*
%
%ADD16MACRO16*%
%AMMACRO39*
4,1,17,.03237,.02176,
.035657,.015808,
.03786,.009377,
.038913,.00266,
.038784,-.004138,
.037476,-.01081,
.03503,-.017153,
.03237,-.02176,
.03739,-.02679,
.041474,-.01989,
.044298,-.012386,
.045776,-.004506,
.045863,.003511,
.044556,.011422,
.041896,.018986,
.037962,.025972,
.03739,.02679,
.03237,.02176,
0.0*
4,1,17,.02176,-.03237,
.015808,-.035657,
.009377,-.03786,
.00266,-.038913,
-.004138,-.038784,
-.01081,-.037476,
-.017153,-.03503,
-.02176,-.03237,
-.02679,-.03739,
-.01989,-.041474,
-.012386,-.044298,
-.004506,-.045776,
.003511,-.045863,
.011422,-.044556,
.018986,-.041896,
.025972,-.037962,
.02679,-.03739,
.02176,-.03237,
0.0*
4,1,17,-.03237,-.02176,
-.035657,-.015808,
-.03786,-.009377,
-.038913,-.00266,
-.038784,.004138,
-.037476,.01081,
-.03503,.017153,
-.03237,.02176,
-.03739,.02679,
-.041474,.01989,
-.044298,.012386,
-.045776,.004506,
-.045863,-.003511,
-.044556,-.011422,
-.041896,-.018986,
-.037962,-.025972,
-.03739,-.02679,
-.03237,-.02176,
0.0*
4,1,17,-.02176,.03237,
-.015808,.035657,
-.009377,.03786,
-.00266,.038913,
.004138,.038784,
.01081,.037476,
.017153,.03503,
.02176,.03237,
.02679,.03739,
.01989,.041474,
.012386,.044298,
.004506,.045776,
-.003511,.045863,
-.011422,.044556,
-.018986,.041896,
-.025972,.037962,
-.02679,.03739,
-.02176,.03237,
0.0*
%
%ADD39MACRO39*%
%ADD27C,.115*%
%AMMACRO10*
4,1,36,0.0,.01,
-.001736,.009848,
-.00342,.009397,
-.005,.00866,
-.006428,.00766,
-.00766,.006428,
-.00866,.005,
-.009397,.00342,
-.009848,.001736,
-.01,0.0,
-.009848,-.001736,
-.009397,-.00342,
-.00866,-.005,
-.00766,-.006428,
-.006428,-.00766,
-.005,-.00866,
-.00342,-.009397,
-.001736,-.009848,
0.0,-.01,
.001736,-.009848,
.00342,-.009397,
.005,-.00866,
.006428,-.00766,
.00766,-.006428,
.00866,-.005,
.009397,-.00342,
.009848,-.001736,
.01,0.0,
.009848,.001736,
.009397,.00342,
.00866,.005,
.00766,.006428,
.006428,.00766,
.005,.00866,
.00342,.009397,
.001736,.009848,
0.0,.01,
180.*
%
%ADD10MACRO10*%
%ADD12C,.172*%
%ADD36C,.158*%
%ADD32O,.068X.093*%
%ADD13C,.168*%
%AMMACRO23*
4,1,36,0.0,.004,
.000695,.003939,
.001368,.003759,
.002,.003464,
.002571,.003064,
.003064,.002571,
.003464,.002,
.003759,.001368,
.003939,.000695,
.004,0.0,
.003939,-.000695,
.003759,-.001368,
.003464,-.002,
.003064,-.002571,
.002571,-.003064,
.002,-.003464,
.001368,-.003759,
.000695,-.003939,
0.0,-.004,
-.000695,-.003939,
-.001368,-.003759,
-.002,-.003464,
-.002571,-.003064,
-.003064,-.002571,
-.003464,-.002,
-.003759,-.001368,
-.003939,-.000695,
-.004,0.0,
-.003939,.000695,
-.003759,.001368,
-.003464,.002,
-.003064,.002571,
-.002571,.003064,
-.002,.003464,
-.001368,.003759,
-.000695,.003939,
0.0,.004,
0.0*
%
%ADD23MACRO23*%
%ADD40C,.006*%
%ADD42R,.057X.111*%
%ADD44C,.09612*%
%ADD50C,.07608*%
%ADD45C,.09606*%
%ADD46C,.1601*%
%ADD41R,.05X.077*%
%ADD47C,.16024*%
%ADD48C,.11706*%
%ADD43R,.072X.096*%
%ADD51C,.18206*%
%ADD49C,.11708*%
G75*
%LPD*%
G75*
G36*
G01X-471400Y-391900D02*
X2244200D01*
Y1528800D01*
X-471400D01*
Y-391900D01*
G37*
%LPC*%
G75*
G36*
G01X1393661Y203980D02*
G02X1395594Y202047I0J-1933D01*
G01Y200000D01*
G03X1401535Y194059I5941J0D01*
G01X1460591D01*
G03X1466532Y200000I0J5941D01*
G01Y202047D01*
G02X1468465Y203980I1933J0D01*
G01X1495827D01*
X1496748Y203797D01*
X1497363Y203386D01*
X1497779Y202763D01*
X1497973Y201835D01*
X1498412Y199951D01*
X1499704Y198060D01*
X1501632Y196788D01*
X1503703Y196382D01*
X1675630D01*
G02X1681500Y190512I0J-5870D01*
G01Y165890D01*
G02X1681000Y165390I-500J0D01*
G01X1675236D01*
G03X1671264Y161417I0J-3972D01*
G01Y125984D01*
G03X1675236Y122012I3972J0D01*
G01X1681000D01*
G02X1681500Y121512I0J-500D01*
G01Y43307D01*
G03X1685472Y39335I3972J0D01*
G01X1685724D01*
G02X1686224Y38835I0J-500D01*
G01Y7874D01*
G02X1680354Y2004I-5870J0D01*
G01X7874D01*
G02X2004Y7874I0J5870D01*
G01Y182900D01*
G02X2504Y183400I500J0D01*
G01X38638D01*
G02X39138Y182900I0J-500D01*
G01Y167913D01*
G03X45902I3382J0D01*
G01Y177500D01*
G02X46402Y178000I500J0D01*
G01X47371D01*
X47471Y178100D01*
X71987D01*
X72087Y178000D01*
X198113D01*
X198213Y178100D01*
X202535D01*
G02X203035Y177600I0J-500D01*
G01Y170551D01*
G03X208976Y164610I5941J0D01*
G01X216850D01*
G03X222791Y170551I0J5941D01*
G01Y198110D01*
G02X228661Y203980I5870J0D01*
G01X372887D01*
G02X374700Y202047I-124J-1933D01*
G01Y200000D01*
G03X380637Y194063I5937J0D01*
G01X381965D01*
G03X382165Y194059I219J5937D01*
G01X441220D01*
G03X447161Y200000I0J5941D01*
G01Y202047D01*
G02X449094Y203980I1933J0D01*
G01X523583D01*
G02X525516Y202047I0J-1933D01*
G01Y200000D01*
G03X531457Y194059I5941J0D01*
G01X590512D01*
G03X596453Y200000I0J5941D01*
G01Y202047D01*
G02X598386Y203980I1933J0D01*
G01X625748D01*
X626669Y203797D01*
X627284Y203386D01*
X627700Y202763D01*
X627894Y201835D01*
X628333Y199951D01*
X629625Y198060D01*
X631553Y196788D01*
X633624Y196382D01*
X799368D01*
X801439Y196788D01*
X803367Y198060D01*
X804659Y199951D01*
X805098Y201835D01*
X805292Y202763D01*
X805708Y203386D01*
X806323Y203797D01*
X807244Y203980D01*
X1244370D01*
G02X1246303Y202047I0J-1933D01*
G01Y200000D01*
G03X1252244Y194059I5941J0D01*
G01X1311299D01*
G03X1317240Y200000I0J5941D01*
G01Y202047D01*
G02X1319173Y203980I1933J0D01*
G01X1393661D01*
G37*
%LPD*%
G75*
G36*
G01X792554Y30690D02*
Y18504D01*
G02X774768I-8893J0D01*
G01Y30690D01*
G03X774164Y32095I-1934J1D01*
G02X771203Y36159I9497J10030D01*
G01X771166Y36236D01*
X770661Y36741D01*
Y37455D01*
X770633Y37536D01*
G02Y46716I13028J4590D01*
G01X770661Y46797D01*
Y47512D01*
X771167Y48018D01*
X771204Y48095D01*
G02X777692Y54583I12457J-5969D01*
G01X777769Y54620D01*
X778276Y55127D01*
X778993D01*
X779073Y55155D01*
G02X788249I4588J-13029D01*
G01X788329Y55127D01*
X789046D01*
X789553Y54620D01*
X789630Y54583D01*
G02X796118Y48095I-5969J-12457D01*
G01X796155Y48018D01*
X796661Y47512D01*
Y46797D01*
X796689Y46716D01*
G02Y37536I-13028J-4590D01*
G01X796661Y37455D01*
Y36741D01*
X796156Y36236D01*
X796119Y36159D01*
G02X793158Y32095I-12458J5966D01*
G03X792554Y30690I1330J-1404D01*
G37*
G36*
G01X1089159Y36155D02*
X1089122Y36232D01*
X1088614Y36740D01*
Y37458D01*
X1088586Y37539D01*
G02Y46714I13029J4588D01*
G01X1088614Y46794D01*
Y47511D01*
X1089121Y48018D01*
X1089158Y48095D01*
G02X1095646Y54583I12457J-5969D01*
G01X1095723Y54620D01*
X1096229Y55126D01*
X1096944D01*
X1097024Y55154D01*
G02X1106206I4591J-13028D01*
G01X1106286Y55126D01*
X1106999D01*
X1107503Y54622D01*
X1107580Y54585D01*
G02X1114074Y48091I-5965J-12459D01*
G01X1114111Y48014D01*
X1114614Y47511D01*
Y46800D01*
X1114642Y46719D01*
G02Y37533I-13027J-4593D01*
G01X1114614Y37453D01*
Y36740D01*
X1114110Y36236D01*
X1114073Y36159D01*
G02X1111112Y32095I-12458J5966D01*
G03X1110508Y30690I1330J-1404D01*
G01Y18504D01*
G02X1097644Y10547I-8893J0D01*
G02X1093930Y14030I3970J7955D01*
G02X1092722Y18504I7685J4475D01*
G01Y30690D01*
G03X1092118Y32095I-1934J1D01*
G02X1089159Y36155I9498J10030D01*
G37*
G36*
G01X5258Y131828D02*
X5221Y131905D01*
X4716Y132410D01*
Y133124D01*
X4688Y133205D01*
G02Y142385I13028J4590D01*
G01X4716Y142466D01*
Y143181D01*
X5222Y143687D01*
X5259Y143764D01*
G02X11747Y150252I12457J-5969D01*
G01X11824Y150289D01*
X12331Y150796D01*
X13048D01*
X13128Y150824D01*
G02X22304I4588J-13029D01*
G01X22384Y150796D01*
X23101D01*
X23608Y150289D01*
X23685Y150252D01*
G02X30173Y143764I-5969J-12457D01*
G01X30210Y143687D01*
X30716Y143181D01*
Y142466D01*
X30744Y142385D01*
G02Y133205I-13028J-4590D01*
G01X30716Y133124D01*
Y132410D01*
X30211Y131905D01*
X30174Y131828D01*
G02X27213Y127764I-12458J5966D01*
G03X26608Y126359I1330J-1405D01*
G01Y114173D01*
G02X8824I-8892J0D01*
G01Y126359D01*
G03X8219Y127764I-1935J0D01*
G02X5258Y131828I9497J10030D01*
G37*
G36*
G01X323106Y175572D02*
Y163386D01*
G02X305320I-8893J0D01*
G01Y175572D01*
G03X304716Y176977I-1934J1D01*
G02X301755Y181041I9497J10030D01*
G01X301718Y181118D01*
X301212Y181624D01*
Y182340D01*
X301184Y182421D01*
G02Y191596I13029J4587D01*
G01X301212Y191676D01*
Y192395D01*
X301721Y192904D01*
X301758Y192981D01*
G02X308241Y199464I12455J-5972D01*
G01X308318Y199501D01*
X308827Y200010D01*
X309547D01*
X309628Y200038D01*
G02X318798I4585J-13030D01*
G01X318879Y200010D01*
X319597D01*
X320105Y199502D01*
X320182Y199465D01*
G02X326670Y192977I-5969J-12457D01*
G01X326707Y192900D01*
X327212Y192395D01*
Y191682D01*
X327240Y191601D01*
G02Y182415I-13027J-4593D01*
G01X327212Y182335D01*
Y181624D01*
X326710Y181122D01*
X326673Y181044D01*
G02X323710Y176977I-12460J5965D01*
G03X323106Y175572I1330J-1404D01*
G37*
G36*
G01X820053Y199464D02*
X820130Y199501D01*
X820638Y200009D01*
X821356D01*
X821436Y200037D01*
G02X830612I4588J-13029D01*
G01X830692Y200009D01*
X831408D01*
X831914Y199503D01*
X831991Y199466D01*
G02X838482Y192975I-5967J-12458D01*
G01X838519Y192898D01*
X839023Y192394D01*
Y191682D01*
X839051Y191601D01*
G02Y182415I-13027J-4593D01*
G01X839023Y182335D01*
Y181623D01*
X838520Y181120D01*
X838483Y181042D01*
G02X835521Y176977I-12459J5966D01*
G03X834916Y175572I1330J-1405D01*
G01Y163386D01*
G02X817131I-8892J0D01*
G01X817132Y175572D01*
G03X816527Y176977I-1935J0D01*
G02X813567Y181039I9498J10030D01*
G01X813530Y181116D01*
X813023Y181623D01*
Y182340D01*
X812995Y182421D01*
G02Y191596I13029J4587D01*
G01X813023Y191676D01*
Y192394D01*
X813531Y192902D01*
X813568Y192979D01*
G02X820053Y199464I12456J-5971D01*
G37*
G36*
G01X1178321D02*
X1178398Y199501D01*
X1178906Y200009D01*
X1179624D01*
X1179704Y200037D01*
G02X1188880I4588J-13029D01*
G01X1188960Y200009D01*
X1189676D01*
X1190182Y199503D01*
X1190259Y199466D01*
G02X1196750Y192975I-5967J-12458D01*
G01X1196787Y192898D01*
X1197291Y192394D01*
Y191682D01*
X1197319Y191601D01*
G02Y182415I-13027J-4593D01*
G01X1197291Y182335D01*
Y181623D01*
X1196788Y181120D01*
X1196751Y181042D01*
G02X1193789Y176977I-12459J5966D01*
G03X1193184Y175572I1330J-1405D01*
G01Y163386D01*
G02X1175400I-8892J0D01*
G01Y175572D01*
G03X1174795Y176977I-1935J0D01*
G02X1171835Y181039I9498J10030D01*
G01X1171798Y181116D01*
X1171291Y181623D01*
Y182340D01*
X1171263Y182421D01*
G02Y191596I13029J4587D01*
G01X1171291Y191676D01*
Y192394D01*
X1171799Y192902D01*
X1171836Y192979D01*
G02X1178321Y199464I12456J-5971D01*
G37*
G36*
G01X430493Y61456D02*
G02X434096Y57853I0J-3603D01*
G01Y55353D01*
G02X427090I-3503J0D01*
G01Y58053D01*
G02X430493Y61456I3403J0D01*
G37*
G36*
G01X579785D02*
G02X583388Y57854I1J-3602D01*
G01Y55354D01*
G02X576382I-3503J0D01*
G01Y58054D01*
G02X579784Y61456I3402J0D01*
G01X579785D01*
G37*
G36*
G01X1300572D02*
G02X1304174Y57854I0J-3602D01*
G01Y55354D01*
G02X1297169I-3503J0D01*
G01X1297170Y58054D01*
G02X1300572Y61456I3402J0D01*
G37*
G36*
G01X1449864Y61455D02*
G02X1453466Y57853I0J-3602D01*
G01Y55353D01*
G02X1446462I-3502J0D01*
G01Y58053D01*
G02X1449864Y61455I3402J0D01*
G37*
G36*
G01X654474Y16390D02*
X654574D01*
Y16590D01*
X659574D01*
Y5296D01*
X654474D01*
Y16390D01*
G37*
G36*
G01X685970D02*
X686070D01*
Y16590D01*
X691070D01*
Y5296D01*
X685970D01*
Y16390D01*
G37*
G36*
G01X1524553D02*
X1524653D01*
Y16590D01*
X1529653D01*
Y5296D01*
X1524553D01*
Y16390D01*
G37*
G36*
G01X1556049D02*
X1556149D01*
Y16590D01*
X1561149D01*
Y5296D01*
X1556049D01*
Y16390D01*
G37*
G36*
G01X646600Y21328D02*
X646700D01*
Y21528D01*
X651700D01*
Y10628D01*
X646600D01*
Y21328D01*
G37*
G36*
G01X678096D02*
X678196D01*
Y21528D01*
X683196D01*
Y10628D01*
X678096D01*
Y21328D01*
G37*
G36*
G01X1516679D02*
X1516779D01*
Y21528D01*
X1521779D01*
Y10628D01*
X1516679D01*
Y21328D01*
G37*
G36*
G01X1548175D02*
X1548275D01*
Y21528D01*
X1553275D01*
Y10628D01*
X1548175D01*
Y21328D01*
G37*
G36*
G01X522472Y22580D02*
X524128D01*
X525300Y21408D01*
Y14752D01*
X524128Y13580D01*
X522472D01*
X521300Y14752D01*
Y21408D01*
X522472Y22580D01*
G37*
G36*
G01X1392551D02*
X1394207D01*
X1395379Y21408D01*
Y14752D01*
X1394207Y13580D01*
X1392551D01*
X1391379Y14752D01*
Y21408D01*
X1392551Y22580D01*
G37*
G36*
G01X399703Y23960D02*
X406359D01*
X407531Y22788D01*
Y21132D01*
X406359Y19960D01*
X399703D01*
X398531Y21132D01*
Y22788D01*
X399703Y23960D01*
G37*
G36*
G01X1269782D02*
X1276438D01*
X1277610Y22788D01*
Y21132D01*
X1276438Y19960D01*
X1269782D01*
X1268610Y21132D01*
Y22788D01*
X1269782Y23960D01*
G37*
G36*
G01X567893Y24500D02*
X574549D01*
X575721Y23328D01*
Y21672D01*
X574549Y20500D01*
X567893D01*
X566721Y21672D01*
Y23328D01*
X567893Y24500D01*
G37*
G36*
G01X1437972D02*
X1444628D01*
X1445800Y23328D01*
Y21672D01*
X1444628Y20500D01*
X1437972D01*
X1436800Y21672D01*
Y23328D01*
X1437972Y24500D01*
G37*
G36*
G01X654474Y32926D02*
X654574D01*
Y33126D01*
X659574D01*
Y21832D01*
X654474D01*
Y32926D01*
G37*
G36*
G01X670222D02*
X670322D01*
Y33126D01*
X675322D01*
Y21832D01*
X670222D01*
Y32926D01*
G37*
G36*
G01X685970D02*
X686070D01*
Y33126D01*
X691070D01*
Y21832D01*
X685970D01*
Y32926D01*
G37*
G36*
G01X1524553D02*
X1524653D01*
Y33126D01*
X1529653D01*
Y21832D01*
X1524553D01*
Y32926D01*
G37*
G36*
G01X1540301D02*
X1540401D01*
Y33126D01*
X1545401D01*
Y21832D01*
X1540301D01*
Y32926D01*
G37*
G36*
G01X1556049D02*
X1556149D01*
Y33126D01*
X1561149D01*
Y21832D01*
X1556049D01*
Y32926D01*
G37*
G36*
G01X646600Y37864D02*
X646700D01*
Y38064D01*
X651700D01*
Y27164D01*
X646600D01*
Y37864D01*
G37*
G36*
G01X662348D02*
X662448D01*
Y38064D01*
X667448D01*
Y27164D01*
X662348D01*
Y37864D01*
G37*
G36*
G01X678096D02*
X678196D01*
Y38064D01*
X683196D01*
Y27164D01*
X678096D01*
Y37864D01*
G37*
G36*
G01X1516679D02*
X1516779D01*
Y38064D01*
X1521779D01*
Y27164D01*
X1516679D01*
Y37864D01*
G37*
G36*
G01X1532427D02*
X1532527D01*
Y38064D01*
X1537527D01*
Y27164D01*
X1532427D01*
Y37864D01*
G37*
G36*
G01X1548175D02*
X1548275D01*
Y38064D01*
X1553275D01*
Y27164D01*
X1548175D01*
Y37864D01*
G37*
G36*
G01X447052Y38200D02*
X454308D01*
X455480Y37028D01*
Y35372D01*
X454308Y34200D01*
X447052D01*
X445880Y35372D01*
Y37028D01*
X447052Y38200D01*
G37*
G36*
G01X1317131D02*
X1324387D01*
X1325559Y37028D01*
Y35372D01*
X1324387Y34200D01*
X1317131D01*
X1315959Y35372D01*
Y37028D01*
X1317131Y38200D01*
G37*
G36*
G01X654474Y49462D02*
X654574D01*
Y49662D01*
X659574D01*
Y38368D01*
X654474D01*
Y49462D01*
G37*
G36*
G01X670222D02*
X670322D01*
Y49662D01*
X675322D01*
Y38368D01*
X670222D01*
Y49462D01*
G37*
G36*
G01X685970D02*
X686070D01*
Y49662D01*
X691070D01*
Y38368D01*
X685970D01*
Y49462D01*
G37*
G36*
G01X1524553D02*
X1524653D01*
Y49662D01*
X1529653D01*
Y38368D01*
X1524553D01*
Y49462D01*
G37*
G36*
G01X1540301D02*
X1540401D01*
Y49662D01*
X1545401D01*
Y38368D01*
X1540301D01*
Y49462D01*
G37*
G36*
G01X1556049D02*
X1556149D01*
Y49662D01*
X1561149D01*
Y38368D01*
X1556049D01*
Y49462D01*
G37*
G36*
G01X646600Y54400D02*
X646700D01*
Y54600D01*
X651700D01*
Y43700D01*
X646600D01*
Y54400D01*
G37*
G36*
G01X662348D02*
X662448D01*
Y54600D01*
X667448D01*
Y43700D01*
X662348D01*
Y54400D01*
G37*
G36*
G01X678096D02*
X678196D01*
Y54600D01*
X683196D01*
Y43700D01*
X678096D01*
Y54400D01*
G37*
G36*
G01X1516679D02*
X1516779D01*
Y54600D01*
X1521779D01*
Y43700D01*
X1516679D01*
Y54400D01*
G37*
G36*
G01X1532427D02*
X1532527D01*
Y54600D01*
X1537527D01*
Y43700D01*
X1532427D01*
Y54400D01*
G37*
G36*
G01X1548175D02*
X1548275D01*
Y54600D01*
X1553275D01*
Y43700D01*
X1548175D01*
Y54400D01*
G37*
G36*
G01X658668Y74450D02*
X664952D01*
X665860Y73542D01*
Y72258D01*
X664952Y71350D01*
X658668D01*
X657760Y72258D01*
Y73542D01*
X658668Y74450D01*
G37*
G36*
G01X756287D02*
X762571D01*
X763479Y73542D01*
Y72258D01*
X762571Y71350D01*
X756287D01*
X755379Y72258D01*
Y73542D01*
X756287Y74450D01*
G37*
G36*
G01X1528747D02*
X1535031D01*
X1535939Y73542D01*
Y72258D01*
X1535031Y71350D01*
X1528747D01*
X1527839Y72258D01*
Y73542D01*
X1528747Y74450D01*
G37*
G36*
G01X1626366D02*
X1632650D01*
X1633558Y73542D01*
Y72258D01*
X1632650Y71350D01*
X1626366D01*
X1625458Y72258D01*
Y73542D01*
X1626366Y74450D01*
G37*
G36*
G01X653758Y98650D02*
X655042D01*
X655950Y97742D01*
Y91458D01*
X655042Y90550D01*
X653758D01*
X652850Y91458D01*
Y97742D01*
X653758Y98650D01*
G37*
G36*
G01X701028D02*
X702312D01*
X703220Y97742D01*
Y91458D01*
X702312Y90550D01*
X701028D01*
X700120Y91458D01*
Y97742D01*
X701028Y98650D01*
G37*
G36*
G01X1523837D02*
X1525121D01*
X1526029Y97742D01*
Y91458D01*
X1525121Y90550D01*
X1523837D01*
X1522929Y91458D01*
Y97742D01*
X1523837Y98650D01*
G37*
G36*
G01X1571107D02*
X1572391D01*
X1573299Y97742D01*
Y91458D01*
X1572391Y90550D01*
X1571107D01*
X1570199Y91458D01*
Y97742D01*
X1571107Y98650D01*
G37*
G36*
G01X777558Y98680D02*
X778842D01*
X779750Y97772D01*
Y91488D01*
X778842Y90580D01*
X777558D01*
X776650Y91488D01*
Y97772D01*
X777558Y98680D01*
G37*
G36*
G01X1647637D02*
X1648921D01*
X1649829Y97772D01*
Y91488D01*
X1648921Y90580D01*
X1647637D01*
X1646729Y91488D01*
Y97772D01*
X1647637Y98680D01*
G37*
G36*
G01X746838Y94380D02*
X753122D01*
X754030Y93472D01*
Y92188D01*
X753122Y91280D01*
X746838D01*
X745930Y92188D01*
Y93472D01*
X746838Y94380D01*
G37*
G36*
G01X1616917D02*
X1623201D01*
X1624109Y93472D01*
Y92188D01*
X1623201Y91280D01*
X1616917D01*
X1616009Y92188D01*
Y93472D01*
X1616917Y94380D01*
G37*
G36*
G01X671996Y94840D02*
X678280D01*
X679188Y93932D01*
Y92648D01*
X678280Y91740D01*
X671996D01*
X671088Y92648D01*
Y93932D01*
X671996Y94840D01*
G37*
G36*
G01X1542075D02*
X1548359D01*
X1549267Y93932D01*
Y92648D01*
X1548359Y91740D01*
X1542075D01*
X1541167Y92648D01*
Y93932D01*
X1542075Y94840D01*
G37*
G36*
G01X723758Y107150D02*
X730042D01*
X730950Y106242D01*
Y104958D01*
X730042Y104050D01*
X723758D01*
X722850Y104958D01*
Y106242D01*
X723758Y107150D01*
G37*
G36*
G01X1593836D02*
X1600120D01*
X1601028Y106242D01*
Y104958D01*
X1600120Y104050D01*
X1593836D01*
X1592928Y104958D01*
Y106242D01*
X1593836Y107150D01*
G37*
G36*
G01X724668Y116940D02*
X730952D01*
X731860Y116032D01*
Y114748D01*
X730952Y113840D01*
X724668D01*
X723760Y114748D01*
Y116032D01*
X724668Y116940D01*
G37*
G36*
G01X1594746D02*
X1601030D01*
X1601938Y116032D01*
Y114748D01*
X1601030Y113840D01*
X1594746D01*
X1593838Y114748D01*
Y116032D01*
X1594746Y116940D01*
G37*
G36*
G01X764161Y121880D02*
X770445D01*
X771353Y120972D01*
Y119688D01*
X770445Y118780D01*
X764161D01*
X763253Y119688D01*
Y120972D01*
X764161Y121880D01*
G37*
G36*
G01X1634239D02*
X1640523D01*
X1641431Y120972D01*
Y119688D01*
X1640523Y118780D01*
X1634239D01*
X1633331Y119688D01*
Y120972D01*
X1634239Y121880D01*
G37*
G36*
G01X745263Y122002D02*
X751547D01*
X752455Y121094D01*
Y119810D01*
X751547Y118902D01*
X745263D01*
X744355Y119810D01*
Y121094D01*
X745263Y122002D01*
G37*
G36*
G01X1615341D02*
X1621625D01*
X1622533Y121094D01*
Y119810D01*
X1621625Y118902D01*
X1615341D01*
X1614433Y119810D01*
Y121094D01*
X1615341Y122002D01*
G37*
G36*
G01X660972Y122550D02*
X667256D01*
X668164Y121642D01*
Y120358D01*
X667256Y119450D01*
X660972D01*
X660064Y120358D01*
Y121642D01*
X660972Y122550D01*
G37*
G36*
G01X1531050D02*
X1537334D01*
X1538242Y121642D01*
Y120358D01*
X1537334Y119450D01*
X1531050D01*
X1530142Y120358D01*
Y121642D01*
X1531050Y122550D01*
G37*
G36*
G01X689319Y123580D02*
X695603D01*
X696511Y122672D01*
Y121388D01*
X695603Y120480D01*
X689319D01*
X688411Y121388D01*
Y122672D01*
X689319Y123580D01*
G37*
G36*
G01X1559397D02*
X1565681D01*
X1566589Y122672D01*
Y121388D01*
X1565681Y120480D01*
X1559397D01*
X1558489Y121388D01*
Y122672D01*
X1559397Y123580D01*
G37*
G36*
G01X754768Y126280D02*
X761052D01*
X761960Y125372D01*
Y124088D01*
X761052Y123180D01*
X754768D01*
X753860Y124088D01*
Y125372D01*
X754768Y126280D01*
G37*
G36*
G01X1624846D02*
X1631130D01*
X1632038Y125372D01*
Y124088D01*
X1631130Y123180D01*
X1624846D01*
X1623938Y124088D01*
Y125372D01*
X1624846Y126280D01*
G37*
G36*
G01X670421Y127480D02*
X676705D01*
X677613Y126572D01*
Y125288D01*
X676705Y124380D01*
X670421D01*
X669513Y125288D01*
Y126572D01*
X670421Y127480D01*
G37*
G36*
G01X1540499D02*
X1546783D01*
X1547691Y126572D01*
Y125288D01*
X1546783Y124380D01*
X1540499D01*
X1539591Y125288D01*
Y126572D01*
X1540499Y127480D01*
G37*
G36*
G01X679970Y131150D02*
X686254D01*
X687162Y130242D01*
Y128958D01*
X686254Y128050D01*
X679970D01*
X679062Y128958D01*
Y130242D01*
X679970Y131150D01*
G37*
G36*
G01X1550048D02*
X1556332D01*
X1557240Y130242D01*
Y128958D01*
X1556332Y128050D01*
X1550048D01*
X1549140Y128958D01*
Y130242D01*
X1550048Y131150D01*
G37*
G36*
G01X83188Y71770D02*
X82328D01*
G02X82327Y73896I3538J1065D01*
G01X83185D01*
G03X83617Y74144I0J500D01*
G02X84604Y75110I2248J-1310D01*
G03X84862Y75548I-242J438D01*
G01Y76390D01*
G02X86870I1004J-3555D01*
G01Y75548D01*
G03X87128Y75110I500J0D01*
G02X88119Y74136I-1262J-2275D01*
G03X88552Y73886I433J250D01*
G01X89408D01*
G02X89560Y72835I-3542J-1049D01*
G02X89404Y71770I-3694J-3D01*
G01X88544D01*
G03X88112Y71522I0J-500D01*
G02X87126Y70559I-2246J1313D01*
G03X86868Y70121I242J-438D01*
G01Y69279D01*
G02X84864I-1002J3556D01*
G01Y70121D01*
G03X84606Y70559I-500J0D01*
G02X83620Y71522I1260J2276D01*
G03X83188Y71770I-432J-252D01*
G37*
G36*
G01Y103266D02*
X82328D01*
G02X82327Y105392I3538J1065D01*
G01X83185D01*
G03X83617Y105640I0J500D01*
G02X84604Y106606I2248J-1310D01*
G03X84862Y107044I-242J438D01*
G01Y107886D01*
G02X86870I1004J-3555D01*
G01Y107044D01*
G03X87128Y106606I500J0D01*
G02X88119Y105632I-1262J-2275D01*
G03X88552Y105382I433J250D01*
G01X89408D01*
G02X89560Y104331I-3542J-1049D01*
G02X89404Y103266I-3694J-3D01*
G01X88544D01*
G03X88112Y103018I0J-500D01*
G02X87126Y102055I-2246J1313D01*
G03X86868Y101617I242J-438D01*
G01Y100775D01*
G02X84864I-1002J3556D01*
G01Y101617D01*
G03X84606Y102055I-500J0D01*
G02X83620Y103018I1260J2276D01*
G03X83188Y103266I-432J-252D01*
G37*
G54D42*
X1336729Y49150D03*
X466650D03*
X1376099Y44032D03*
X506020D03*
X1336729Y32615D03*
X466650D03*
X1376099Y27497D03*
X506020D03*
G54D44*
X1647618Y132244D03*
X1572775D03*
X777539D03*
X702697D03*
G54D50*
X40827Y147638D03*
Y29528D03*
G54D45*
X1600374Y132244D03*
X1525531D03*
X1412164Y56653D03*
X1262872Y56654D03*
X730295Y132244D03*
X655453D03*
X542085Y56654D03*
X392793Y56653D03*
G54D46*
X1378938Y176650D03*
X508859D03*
G54D41*
X1637367Y111850D03*
X1627918D03*
X1618470D03*
X1609021D03*
X1562524D03*
X1553075D03*
X1543627D03*
X1534178D03*
X767288D03*
X757839D03*
X748391D03*
X738942D03*
X692446D03*
X682997D03*
X673549D03*
X664100D03*
X1638942Y101968D03*
X1629493D03*
X1620045D03*
X1610596D03*
X1564099D03*
X1554650D03*
X1545202D03*
X1535753D03*
X768863D03*
X759414D03*
X749966D03*
X740517D03*
X694021D03*
X684572D03*
X675124D03*
X665675D03*
G54D47*
X1333938Y176650D03*
X463859D03*
G54D48*
X1221732Y37400D03*
G54D43*
X1291985Y40500D03*
X1273087D03*
X571198D03*
X552300D03*
X1441277Y40499D03*
X1422379D03*
X421906D03*
X403008D03*
G54D51*
X17717Y18504D03*
X1670512D03*
G54D49*
X351654Y37401D03*
G54D18*
X64500Y165200D03*
X99100Y127470D03*
X89400Y165300D03*
X111958Y73600D03*
X121958Y70900D03*
X116958Y68600D03*
X106958Y68500D03*
X122758Y82442D03*
X117158Y82542D03*
X112158Y82342D03*
X106958Y82142D03*
X102590Y115680D03*
X115400Y120270D03*
X107390Y125110D03*
X119800Y124390D03*
X108900Y137300D03*
X114300Y134900D03*
X119700Y132400D03*
X111500Y129900D03*
X105800Y165400D03*
X125558Y79642D03*
X128600Y114510D03*
X132500Y110100D03*
X125000Y126400D03*
X350700Y121642D03*
X345900Y125100D03*
X347350Y143750D03*
X346906Y137693D03*
X357800Y114657D03*
X357600Y108561D03*
X356861Y102961D03*
X367200Y124000D03*
X405531Y21960D03*
X400531D03*
X400100Y13900D03*
X412800Y16200D03*
X410906Y46100D03*
X414055Y46200D03*
X412480Y80900D03*
X403032Y89532D03*
X415630Y80700D03*
X412300Y85600D03*
X421929Y78400D03*
X409331Y88600D03*
X406181Y82300D03*
X399882Y79318D03*
X447880Y36200D03*
X453480D03*
X453900Y92300D03*
X466200Y87558D03*
X453300Y86800D03*
X451100Y81400D03*
X452100Y97000D03*
X466100Y83258D03*
X452000Y102200D03*
X466300Y100900D03*
X488800Y73700D03*
Y93800D03*
X511600Y108000D03*
X523300Y15580D03*
Y20580D03*
X525700Y99300D03*
X519400Y96400D03*
X520439Y91000D03*
X516500Y87442D03*
X526612Y142000D03*
X559425Y13575D03*
X560198Y46100D03*
X558623Y79200D03*
X552324Y78500D03*
X549174Y89400D03*
X582416Y16466D03*
X573721Y22500D03*
X568721D03*
X563347Y46100D03*
X571221Y79700D03*
X568072Y81500D03*
X564922Y81900D03*
X561772Y80800D03*
X563800Y87700D03*
X604400Y96000D03*
X604200Y107400D03*
X614900Y90157D03*
X615600Y95139D03*
X615500Y100157D03*
X622658Y112158D03*
X622200Y120258D03*
X615500Y105157D03*
X626173Y148400D03*
X617949Y147000D03*
X659310Y72900D03*
X664310D03*
X654400Y92100D03*
Y97100D03*
X672638Y93290D03*
X666614Y121000D03*
X661614D03*
X671063Y125930D03*
X676063D03*
X677638Y93290D03*
X689961Y122030D03*
X694961D03*
X680612Y129600D03*
X685612D03*
X701100Y16900D03*
X701670Y97100D03*
Y92100D03*
X724400Y105600D03*
X729400D03*
X730310Y115390D03*
X725310D03*
X761929Y72900D03*
X756929D03*
X752480Y92830D03*
X747480D03*
X745905Y120452D03*
X750905D03*
X764803Y120330D03*
X760410Y124730D03*
X755410D03*
X778200Y92130D03*
Y97130D03*
X769803Y120330D03*
X1226900Y119561D03*
Y114043D03*
X1227000Y108361D03*
X1227100Y102861D03*
X1219600Y129400D03*
X1219400Y123900D03*
X1211200Y144900D03*
X1217405Y143895D03*
X1238900Y123300D03*
X1238100Y127900D03*
X1270610Y21960D03*
X1268700Y14000D03*
X1273111Y89100D03*
X1269961Y78400D03*
X1275610Y21960D03*
X1289775Y11975D03*
X1284134Y46100D03*
X1280985Y46200D03*
X1292008Y80192D03*
X1288859Y78400D03*
X1279410Y87200D03*
X1285709Y84300D03*
X1276260Y79000D03*
X1282559Y85700D03*
X1317959Y36200D03*
X1323559D03*
X1333400Y82900D03*
X1323000Y99239D03*
X1321400Y92800D03*
X1329500Y81400D03*
X1321500Y82600D03*
X1322500Y87800D03*
X1335600Y96500D03*
X1358200Y69000D03*
X1358600Y73700D03*
X1345100Y105500D03*
X1387400Y87242D03*
X1389900Y97600D03*
X1371600Y96000D03*
X1393379Y20580D03*
Y15580D03*
X1395200Y99500D03*
X1391000Y92400D03*
X1429525Y13775D03*
X1433426Y46100D03*
X1430277D03*
X1422403Y78400D03*
X1434200Y88100D03*
X1435001Y81700D03*
X1431851Y80200D03*
X1428702Y79002D03*
X1429400Y88500D03*
X1443800Y22500D03*
X1438800D03*
X1454600Y17600D03*
X1441300Y79100D03*
X1438151Y81100D03*
X1472400Y102700D03*
X1474200Y106600D03*
X1484700Y93057D03*
X1485000Y98057D03*
X1484900Y103257D03*
X1492300Y117558D03*
X1484800Y109357D03*
X1492042Y126358D03*
X1495800Y147800D03*
X1487600Y147000D03*
X1524478Y97100D03*
Y92100D03*
X1534388Y72900D03*
X1529388D03*
X1542716Y93290D03*
X1547716D03*
X1531692Y121000D03*
X1536692D03*
X1546141Y125930D03*
X1550690Y129600D03*
X1541141Y125930D03*
X1570800Y18900D03*
X1571748Y92100D03*
Y97100D03*
X1565039Y122030D03*
X1560039D03*
X1555690Y129600D03*
X1594478Y105600D03*
X1595388Y115390D03*
X1617558Y92830D03*
X1599478Y105600D03*
X1600388Y115390D03*
X1615983Y120452D03*
X1627007Y72900D03*
X1632007D03*
X1622558Y92830D03*
X1620983Y120452D03*
X1639881Y120330D03*
X1634881D03*
X1625488Y124730D03*
X1630488D03*
X1648278Y97130D03*
Y92130D03*
G54D17*
X51900Y162300D03*
X53200Y169500D03*
X76900Y20200D03*
X65600Y160400D03*
X57200Y165300D03*
X73200Y162100D03*
X62200Y169900D03*
X70400Y170000D03*
X90200Y22400D03*
X94900Y144500D03*
X83800Y154500D03*
X99000Y148900D03*
X78800Y158000D03*
X93900Y162900D03*
X90200Y169500D03*
X81600Y162600D03*
X92600Y154800D03*
X100700Y163400D03*
X89000Y150200D03*
X88000Y158900D03*
X83500Y169700D03*
X78200Y169900D03*
X96900Y169500D03*
X98000Y157100D03*
X102500Y29400D03*
X107200Y19300D03*
X121200Y33900D03*
X102000Y141900D03*
X114000Y145200D03*
X119900Y143200D03*
X108600Y143100D03*
X111800Y151800D03*
X104900Y157400D03*
X120500Y157200D03*
X111900Y164800D03*
X118100Y162100D03*
X104500Y150300D03*
X110900Y159200D03*
X118400Y152000D03*
X106500Y170300D03*
X115300Y170200D03*
X123900Y41000D03*
X138700Y63500D03*
X144100Y72900D03*
X139800Y90200D03*
X131400Y91300D03*
X129200Y101300D03*
Y142400D03*
X126600Y149500D03*
X165600Y19400D03*
X168100Y48400D03*
X151500Y35800D03*
X159800Y65100D03*
X161800Y86800D03*
X158200Y102400D03*
X184100Y36600D03*
X174300Y73300D03*
X181400Y84700D03*
X194400Y20200D03*
X197800Y30900D03*
Y48000D03*
X214700Y35800D03*
X195600Y64100D03*
X206700Y72700D03*
X225800Y19600D03*
X229200Y30900D03*
X216400Y100500D03*
X254400Y19200D03*
X257800Y51200D03*
X244900Y36600D03*
X254400Y74300D03*
X251600Y100100D03*
X252200Y159400D03*
X252800Y179900D03*
X268300Y36200D03*
X283600Y69500D03*
X273300Y94900D03*
X281800Y100900D03*
X267700Y145200D03*
X280000Y159800D03*
X281000Y180700D03*
X307800Y101100D03*
X300300Y140000D03*
X350000Y161800D03*
X350200Y181100D03*
X466654Y29922D03*
Y18898D03*
Y13386D03*
Y51969D03*
Y46457D03*
Y35433D03*
X474528Y8268D03*
X490276D03*
X474528Y30315D03*
X482402Y29922D03*
X490276Y30315D03*
X474528Y24803D03*
X490276D03*
X482402Y18898D03*
X474528Y13780D03*
X482402Y13386D03*
X490276Y13780D03*
X474528Y52362D03*
X482402Y51969D03*
X490276Y52362D03*
X474528Y46851D03*
X482402Y46457D03*
X490276Y46851D03*
X474528Y41339D03*
X482402Y40945D03*
X490276Y41339D03*
X482402Y35433D03*
X490276Y35827D03*
X506024Y8268D03*
X498150Y29922D03*
X506024Y30315D03*
Y24803D03*
X498150Y18898D03*
Y13386D03*
X506024Y13780D03*
X498150Y51969D03*
Y46457D03*
X506024Y46851D03*
Y41339D03*
X498150Y35433D03*
X649173Y29922D03*
Y18898D03*
Y13386D03*
Y51969D03*
Y46457D03*
Y35433D03*
X657047Y8268D03*
X672795D03*
X657047Y30315D03*
X664921Y29922D03*
X672795Y30315D03*
X657047Y24803D03*
X672795D03*
X664921Y18898D03*
X657047Y13780D03*
X664921Y13386D03*
X672795Y13780D03*
X664921Y51969D03*
X657047Y46851D03*
X664921Y46457D03*
X672795Y46851D03*
X657047Y41339D03*
X672795D03*
X664921Y35433D03*
X688543Y8268D03*
X680669Y29922D03*
X688543Y30315D03*
Y24803D03*
X680669Y18898D03*
Y13386D03*
X688543Y13780D03*
X680669Y51969D03*
Y46457D03*
X688543Y46851D03*
Y41339D03*
X680669Y35433D03*
X813700Y43900D03*
X809700Y86500D03*
X839700D03*
X838300Y128100D03*
X855400Y152400D03*
X857000Y189800D03*
X869700Y86500D03*
X868300Y128100D03*
X899700Y86500D03*
X898300Y128100D03*
X885400Y152400D03*
X887000Y189800D03*
X929700Y86500D03*
X928300Y128100D03*
X915400Y152400D03*
X917000Y189800D03*
X945400Y152400D03*
X947000Y189800D03*
X959000Y18000D03*
X959700Y86500D03*
X958300Y128100D03*
X975400Y152400D03*
X989700Y86500D03*
X988300Y128100D03*
X977000Y189800D03*
X1018300Y128100D03*
X1005400Y152400D03*
X1007000Y189800D03*
X1043000Y45500D03*
X1031900Y84100D03*
X1035400Y152400D03*
X1037000Y189800D03*
X1063700Y15300D03*
X1061900Y84100D03*
X1048300Y128100D03*
X1065400Y152400D03*
X1067000Y189800D03*
X1073000Y45500D03*
X1078300Y128100D03*
X1091900Y84100D03*
X1108300Y128100D03*
X1095400Y152400D03*
X1097000Y189800D03*
X1120900Y64500D03*
X1121900Y84100D03*
X1125400Y152400D03*
X1127000Y189800D03*
X1147100Y64500D03*
X1151900Y84100D03*
X1155400Y152400D03*
X1157000Y189800D03*
X1344607Y8268D03*
X1336733Y29922D03*
X1344607Y30315D03*
Y24803D03*
X1336733Y18898D03*
Y13386D03*
X1344607Y13780D03*
X1336733Y51969D03*
X1344607Y52362D03*
X1336733Y46457D03*
X1344607Y46851D03*
Y41339D03*
X1336733Y35433D03*
X1360355Y8268D03*
X1352481Y29922D03*
X1360355Y30315D03*
Y24803D03*
X1352481Y18898D03*
Y13386D03*
X1360355Y13780D03*
X1352481Y51969D03*
X1360355Y52362D03*
X1352481Y46457D03*
X1360355Y46851D03*
X1352481Y40945D03*
X1360355Y41339D03*
X1352481Y35433D03*
X1360355Y35827D03*
X1376103Y8268D03*
X1368229Y29922D03*
X1376103Y30315D03*
Y24803D03*
X1368229Y18898D03*
Y13386D03*
X1376103Y13780D03*
X1368229Y51969D03*
Y46457D03*
X1376103Y46851D03*
Y41339D03*
X1368229Y35433D03*
X1527126Y8268D03*
X1519252Y29922D03*
X1527126Y30315D03*
Y24803D03*
X1519252Y18898D03*
Y13386D03*
X1527126Y13780D03*
X1519252Y51969D03*
Y46457D03*
X1527126Y46851D03*
Y41339D03*
X1519252Y35433D03*
X1542874Y8268D03*
X1535000Y29922D03*
X1542874Y30315D03*
X1550748Y29922D03*
X1542874Y24803D03*
X1535000Y18898D03*
X1550748D03*
X1535000Y13386D03*
X1542874Y13780D03*
X1550748Y13386D03*
X1535000Y51969D03*
X1550748D03*
X1535000Y46457D03*
X1542874Y46851D03*
X1550748Y46457D03*
X1542874Y41339D03*
X1535000Y35433D03*
X1550748D03*
X1558622Y8268D03*
Y30315D03*
Y24803D03*
Y13780D03*
Y46851D03*
Y41339D03*
G54D28*
X367402Y11810D03*
Y19684D03*
Y27558D03*
X359528Y11810D03*
Y19684D03*
Y27558D03*
X367402Y43306D03*
Y51180D03*
X359528Y43306D03*
Y51180D03*
X367402Y59054D03*
X359528D03*
X1229606Y11810D03*
Y19684D03*
Y27558D03*
Y43306D03*
Y51180D03*
Y59054D03*
X1237480Y11810D03*
Y19684D03*
Y27558D03*
Y43306D03*
Y51180D03*
Y59054D03*
G54D15*
X44528Y41339D03*
Y53150D03*
Y64961D03*
Y76772D03*
Y88583D03*
Y100394D03*
Y112205D03*
Y124016D03*
Y135827D03*
G54D19*
X85866Y72835D03*
Y104331D03*
G54D14*
X40827Y29528D03*
Y147638D03*
G54D33*
X439744Y60217D03*
X589036D03*
X1309823D03*
X1459114D03*
G54D34*
X468859Y115666D03*
Y141650D03*
X488859Y115666D03*
X478859D03*
X483859Y125666D03*
X473859D03*
X478859Y141650D03*
X488859D03*
X473859Y151650D03*
X483859D03*
X498859Y115666D03*
X503859Y125666D03*
X493859D03*
X498859Y141650D03*
X493859Y151650D03*
X503859D03*
X1338938Y115666D03*
X1343938Y125666D03*
X1338938Y141650D03*
X1343938Y151650D03*
X1358938Y115666D03*
X1348938D03*
X1363938Y125666D03*
X1353938D03*
X1348938Y141650D03*
X1358938D03*
X1353938Y151650D03*
X1363938D03*
X1368938Y115666D03*
X1373938Y125666D03*
X1368938Y141650D03*
X1373938Y151650D03*
G54D11*
X9088Y80158D03*
Y91958D03*
X19088Y80158D03*
Y91958D03*
X109288Y92458D03*
X119288D03*
X109288Y103958D03*
X119288D03*
G54D30*
X392795Y56653D03*
X542087Y56654D03*
X655453Y132244D03*
X702697D03*
X730295D03*
X777539D03*
X1262874Y56654D03*
X1412166Y56653D03*
X1525531Y132244D03*
X1572775D03*
X1600374D03*
X1647618D03*
G54D20*
X81929Y76772D03*
Y68898D03*
X89803Y76772D03*
Y68898D03*
X81929Y100394D03*
Y92520D03*
Y84646D03*
X89803Y100394D03*
Y92520D03*
Y84646D03*
X81929Y108268D03*
G54D24*
X102400Y59600D03*
G54D37*
X477630Y88900D03*
X575600Y7600D03*
X571500Y7500D03*
X567500Y7300D03*
X563100Y7200D03*
X1433700Y8000D03*
X1442400Y8200D03*
X1438000Y8100D03*
X1446300Y8300D03*
G54D29*
X392776Y32264D03*
X383642Y50375D03*
Y70060D03*
Y88564D03*
X411673Y32264D03*
X430571D03*
X439744Y50375D03*
Y70060D03*
Y88564D03*
X532934Y50375D03*
Y70060D03*
Y88564D03*
X542068Y32264D03*
X560965D03*
X579863D03*
X589036Y50375D03*
Y70060D03*
Y88564D03*
X1262855Y32264D03*
X1253721Y50375D03*
Y70060D03*
Y88564D03*
X1281752Y32264D03*
X1300650D03*
X1309823Y50375D03*
Y70060D03*
Y88564D03*
X1412146Y32264D03*
X1403012Y50375D03*
Y70060D03*
Y88564D03*
X1431043Y32264D03*
X1449941D03*
X1459114Y50375D03*
Y70060D03*
Y88564D03*
G54D22*
X123100Y49600D03*
X143300Y27300D03*
X143800Y53600D03*
X144500Y40000D03*
X133100Y71300D03*
X144200Y96300D03*
X143000Y105700D03*
X141900Y154700D03*
X134800Y164000D03*
X144700Y149200D03*
X137100Y158600D03*
X137000Y170400D03*
X127400D03*
X150300Y20200D03*
X166500Y34700D03*
X153100Y49600D03*
X148800Y85000D03*
X163500Y144900D03*
X150300Y144600D03*
X156000Y138200D03*
X156500Y144800D03*
X169900Y146800D03*
X164400Y138200D03*
X169400Y153600D03*
X155600Y157900D03*
X162100Y164300D03*
X168000Y161200D03*
X149300Y164100D03*
X163200Y151600D03*
X162000Y159400D03*
X148000Y158800D03*
X152600Y152000D03*
X155900Y170000D03*
X163800Y170100D03*
X148600D03*
X180300Y20200D03*
X183100Y49600D03*
X191700Y75400D03*
X175000Y62300D03*
X174200Y96300D03*
X190400Y136600D03*
X191200Y142400D03*
X178100Y144600D03*
X184000Y138800D03*
X173600Y138700D03*
X185800Y145400D03*
X190000Y149800D03*
X179300Y156400D03*
X187100Y155800D03*
X192100Y163500D03*
X176300Y164400D03*
X175500Y151300D03*
X173700Y158700D03*
X190400Y169800D03*
X182600Y152000D03*
X171300Y170000D03*
X177800Y170400D03*
X210300Y20200D03*
X213100Y49600D03*
X209400Y60900D03*
X204200Y96300D03*
X196200Y102300D03*
X211300Y138600D03*
X204200Y139200D03*
X195900Y146300D03*
X213300Y146800D03*
X197300Y139100D03*
X205100Y147700D03*
X201500Y154400D03*
X213500Y155400D03*
X197100Y160800D03*
X194600Y154800D03*
X227100Y43000D03*
X234200Y96300D03*
X225600Y104500D03*
X234500Y138700D03*
X230600Y146400D03*
X218100Y140500D03*
X224400Y138200D03*
X236800Y165000D03*
X238800Y157500D03*
X231600Y155100D03*
X221800Y149400D03*
X236500Y185900D03*
X235400Y172900D03*
X240300Y20200D03*
X243100Y49600D03*
X248600Y142900D03*
X242600Y140100D03*
X254400Y138200D03*
X239600Y148700D03*
X245100Y165200D03*
X255400Y148400D03*
X245600Y157000D03*
X248400Y149800D03*
X239800Y178700D03*
X243300Y185600D03*
X242300Y171800D03*
X252600Y192000D03*
X242400Y193300D03*
X270300Y20200D03*
X273100Y49600D03*
X264200Y96300D03*
X262900Y104900D03*
X284400Y138200D03*
X265300Y170000D03*
X282600Y192000D03*
X294200Y96300D03*
X287600Y150000D03*
X292800Y169800D03*
X324200Y96300D03*
X314600Y104100D03*
X310200Y135900D03*
X338300Y162900D03*
Y183800D03*
X359200Y164900D03*
X359100Y184400D03*
X466654Y7874D03*
Y24410D03*
Y40945D03*
X482402Y7874D03*
Y24410D03*
X474528Y19292D03*
X490276D03*
X474528Y35827D03*
X498150Y7874D03*
Y24410D03*
X506024Y19292D03*
Y52362D03*
X498150Y40945D03*
X506024Y35827D03*
X649173Y7874D03*
Y24410D03*
Y40945D03*
X664921Y7874D03*
Y24410D03*
X657047Y19292D03*
X672795D03*
X657047Y52362D03*
X672795D03*
X664921Y40945D03*
X657047Y35827D03*
X672795D03*
X680669Y7874D03*
Y24410D03*
X688543Y19292D03*
Y52362D03*
X680669Y40945D03*
X688543Y35827D03*
X806800Y26700D03*
X810700Y65200D03*
X836800Y26700D03*
X825200Y111700D03*
X840700Y65200D03*
X855200Y111700D03*
X855400Y173000D03*
X866800Y26700D03*
X870700Y65200D03*
X896800Y26700D03*
X900700Y65200D03*
X885200Y111700D03*
X885400Y173000D03*
X926800Y26700D03*
X915200Y111700D03*
X915400Y173000D03*
X930700Y65200D03*
X945200Y111700D03*
X945400Y173000D03*
X956800Y26700D03*
X960700Y65200D03*
X975200Y111700D03*
X975400Y173000D03*
X986800Y26700D03*
X990700Y65200D03*
X1018800Y26300D03*
X1005200Y111700D03*
X1005400Y173000D03*
X1022700Y64800D03*
X1037200Y111300D03*
X1035400Y173000D03*
X1048800Y26300D03*
X1052700Y64800D03*
X1067200Y111300D03*
X1067400Y172600D03*
X1078800Y26300D03*
X1082700Y64800D03*
X1097200Y111300D03*
X1097400Y172600D03*
X1136600Y19700D03*
X1135400Y41000D03*
X1127200Y111300D03*
X1127400Y172600D03*
X1157400D03*
X1336733Y7874D03*
Y24410D03*
X1344607Y19292D03*
X1336733Y40945D03*
X1344607Y35827D03*
X1352481Y7874D03*
Y24410D03*
X1360355Y19292D03*
X1368229Y7874D03*
Y24410D03*
X1376103Y19292D03*
Y52362D03*
X1368229Y40945D03*
X1376103Y35827D03*
X1519252Y7874D03*
Y24410D03*
X1527126Y19292D03*
Y52362D03*
X1519252Y40945D03*
X1527126Y35827D03*
X1535000Y7874D03*
X1550748D03*
X1535000Y24410D03*
X1550748D03*
X1542874Y19292D03*
Y52362D03*
X1535000Y40945D03*
X1550748D03*
X1542874Y35827D03*
X1558622Y19292D03*
Y52362D03*
Y35827D03*
G54D26*
X343780Y11810D03*
Y19684D03*
Y27558D03*
X335906Y11810D03*
Y19684D03*
Y27558D03*
X343780Y43306D03*
Y51180D03*
X335906Y43306D03*
Y51180D03*
X343780Y59054D03*
X335906D03*
X1205984Y11810D03*
Y19684D03*
Y27558D03*
Y43306D03*
Y51180D03*
Y59054D03*
X1213858Y11810D03*
Y19684D03*
Y27558D03*
Y43306D03*
Y51180D03*
Y59054D03*
G54D35*
X452875Y131650D03*
X455867Y153658D03*
X452875Y194642D03*
X516851Y140666D03*
X519843Y115666D03*
Y194642D03*
X1322954Y131650D03*
Y194642D03*
X1325946Y153658D03*
X1389922Y115666D03*
X1386930Y140666D03*
X1389922Y194642D03*
G54D31*
X383642Y40532D03*
Y79902D03*
X396122Y99587D03*
X383642Y119272D03*
Y158642D03*
X417382Y99587D03*
X405964Y178327D03*
X439744Y99587D03*
Y138957D03*
Y178327D03*
X532934Y40532D03*
Y79902D03*
Y119272D03*
Y158642D03*
X545414Y99587D03*
X555256Y178327D03*
X566674Y99587D03*
X589036D03*
Y138957D03*
Y178327D03*
X1253721Y40532D03*
Y79902D03*
Y119272D03*
Y158642D03*
X1266201Y99587D03*
X1276043Y178327D03*
X1287461Y99587D03*
X1309823D03*
Y138957D03*
Y178327D03*
X1403012Y40532D03*
Y79902D03*
Y119272D03*
Y158642D03*
X1415492Y99587D03*
X1436752D03*
X1425334Y178327D03*
X1459114Y99587D03*
Y138957D03*
Y178327D03*
G54D38*
X639283Y108622D03*
Y167677D03*
X793693Y108622D03*
Y167677D03*
X1509362Y108622D03*
Y167677D03*
X1663772Y108622D03*
Y167677D03*
G54D21*
X89803Y108268D03*
G54D25*
X306772Y19685D03*
Y41850D03*
Y67913D03*
X612047Y19685D03*
Y41850D03*
Y67913D03*
X1176851Y19685D03*
Y41850D03*
Y67913D03*
X1482126Y19685D03*
Y41850D03*
Y67913D03*
G54D16*
X56339Y41339D03*
Y53150D03*
Y64961D03*
Y76772D03*
Y88583D03*
Y100394D03*
Y112205D03*
Y124016D03*
Y135827D03*
G54D39*
X641212Y132244D03*
X791764D03*
X1511291D03*
X1661843D03*
G54D10*
X8221Y28000D03*
Y9008D03*
X4287Y18504D03*
X17717Y5074D03*
X27213Y28000D03*
X31147Y18504D03*
X27213Y9008D03*
X17717Y31934D03*
X1661016Y28000D03*
Y9008D03*
X1657082Y18504D03*
X1670512Y5074D03*
X1680008Y28000D03*
X1683942Y18504D03*
X1680008Y9008D03*
X1670512Y31934D03*
G54D27*
X351654Y37400D03*
X1221732D03*
G54D12*
X17717Y18504D03*
X1670512D03*
G54D36*
X463859Y176650D03*
X508859D03*
X1333938D03*
X1378938D03*
G54D13*
X17716Y114173D03*
X314213Y163386D03*
X783661Y18504D03*
X826024Y163386D03*
X1101615Y18504D03*
X1184292Y163386D03*
G54D32*
X430591Y56653D03*
X579883Y56654D03*
X1300670D03*
X1449962Y56653D03*
G54D23*
X120500Y59400D03*
X114400Y59700D03*
X107500Y59500D03*
X141400Y164800D03*
X129000D03*
X169200Y165200D03*
X155500Y164800D03*
X183300Y164700D03*
X346800Y113500D03*
X345400Y107600D03*
X346200Y102500D03*
X362500Y97100D03*
X357600Y97000D03*
X397800Y23600D03*
Y19500D03*
X398307Y35000D03*
Y46100D03*
X396732Y78932D03*
X417900Y6700D03*
X414900Y6500D03*
X410200Y6700D03*
X404400Y6800D03*
X408200Y23500D03*
Y19900D03*
X417205Y35000D03*
X407600D03*
X407756Y46100D03*
X417205D03*
X426500Y35000D03*
X426654Y46100D03*
X426200Y78100D03*
X446000Y38400D03*
Y33900D03*
X455400Y34000D03*
Y38600D03*
X465600Y55900D03*
X463435Y79865D03*
X474500Y3900D03*
X490200Y4000D03*
X488000Y89800D03*
X507200Y4200D03*
X505700Y90200D03*
X520900Y22500D03*
X525600Y22600D03*
Y13900D03*
X520800Y13800D03*
X556900Y35000D03*
X547599D03*
X557048Y46100D03*
X547599D03*
X546024Y79200D03*
X567100Y20500D03*
X575900Y20800D03*
X575800Y24300D03*
X567000Y24400D03*
X575946Y46100D03*
X566497D03*
X575800Y35000D03*
X566497D03*
X574371Y78400D03*
X626100Y99900D03*
X625600Y95400D03*
X625700Y90100D03*
X626600Y106100D03*
X648300Y55600D03*
X651500Y94700D03*
X651100Y91100D03*
X655200Y4100D03*
X661600Y75900D03*
X667200Y75700D03*
X665100Y55900D03*
X670414Y96486D03*
X658400Y102500D03*
X659390Y117490D03*
X668839Y117661D03*
X667500Y126200D03*
X688800Y4100D03*
X680300Y75600D03*
X681600Y55500D03*
X698400Y90300D03*
X689723Y89400D03*
X689311Y96311D03*
X679862Y96538D03*
X678288Y122700D03*
X697185Y117385D03*
X687736Y118700D03*
X685600Y133200D03*
X680900D03*
X701732Y101968D03*
X740300Y87300D03*
X735807Y96593D03*
X745256Y96044D03*
X743681Y117400D03*
X731950Y111850D03*
X723500Y118900D03*
X722400Y102300D03*
X730900Y108900D03*
X753100Y75100D03*
X765600Y74800D03*
X764153Y96153D03*
X754704Y96196D03*
X762578Y117300D03*
X753130D03*
X754300Y121400D03*
X764000Y124700D03*
X774600Y90300D03*
X776032Y101968D03*
X772027Y117300D03*
X1223200Y99000D03*
X1218000Y99100D03*
X1216500Y119500D03*
X1216700Y114400D03*
X1216500Y108300D03*
X1216400Y102600D03*
X1229800Y96400D03*
X1273000Y6100D03*
X1267700Y22900D03*
Y19700D03*
X1268386Y35000D03*
Y46100D03*
X1266811Y78300D03*
X1276700Y5900D03*
X1280900D03*
X1285800D03*
X1278700Y19800D03*
Y23000D03*
X1296600Y35000D03*
X1277700D03*
X1287284D03*
X1296733Y46100D03*
X1287284D03*
X1277835D03*
X1295158Y79158D03*
X1315879Y38200D03*
X1315979Y33900D03*
X1325279Y38600D03*
Y33800D03*
X1335300Y55600D03*
X1340400Y90800D03*
X1360600Y4000D03*
X1344700Y4100D03*
X1359000Y91000D03*
X1376300Y4000D03*
X1371600Y86463D03*
X1395679Y22600D03*
X1390979Y22500D03*
X1390879Y13800D03*
X1395679Y13900D03*
X1417678Y46100D03*
X1427127D03*
X1417678Y35000D03*
X1427000D03*
X1416103Y78400D03*
X1436500Y23900D03*
Y20700D03*
X1445900Y20800D03*
X1445700Y24400D03*
X1446025Y46100D03*
X1436576D03*
X1445900Y35000D03*
X1436576D03*
X1444450Y78300D03*
X1494200Y97800D03*
X1495000Y92800D03*
X1494700Y111200D03*
X1494500Y102700D03*
X1527200Y3800D03*
X1518200Y55600D03*
X1521579Y94700D03*
X1521179Y91100D03*
X1550500Y75500D03*
X1537279Y75700D03*
X1531679Y75900D03*
X1535300Y55800D03*
X1549940Y96538D03*
X1540492Y96486D03*
X1528478Y102500D03*
X1548366Y122700D03*
X1538917Y117661D03*
X1529468Y117490D03*
X1550979Y133200D03*
X1537579Y126200D03*
X1559000Y4200D03*
X1551800Y55700D03*
X1559802Y89400D03*
X1559389Y96311D03*
X1568479Y90300D03*
X1571810Y101968D03*
X1557814Y118700D03*
X1567263Y117385D03*
X1555679Y133200D03*
X1592900Y101700D03*
X1593300Y119000D03*
X1610379Y87300D03*
X1605885Y96593D03*
X1615334Y96044D03*
X1613759Y117400D03*
X1602028Y111850D03*
X1600900Y108700D03*
X1635679Y74800D03*
X1623179Y75100D03*
X1624782Y96196D03*
X1634231Y96153D03*
X1623208Y117300D03*
X1642105D03*
X1632656D03*
X1624300Y121500D03*
X1634179Y124300D03*
X1644679Y90300D03*
X1646110Y101968D03*
X1676100Y78900D03*
%LPC*%
G75*
G54D40*
G01X457212Y-338900D02*
Y-343900D01*
G01X455755Y-338900D02*
X458669D01*
G01X463579Y-343900D02*
X461045D01*
Y-338900D01*
X463579D01*
G01X462565Y-341317D02*
X461045D01*
G01X466145Y-338900D02*
Y-343900D01*
X468679D01*
G01X472512Y-344067D02*
X472385Y-343983D01*
Y-343817D01*
X472512Y-343733D01*
X472639Y-343817D01*
Y-343983D01*
X472512Y-344067D01*
G01Y-341817D02*
X472385Y-341733D01*
Y-341567D01*
X472512Y-341483D01*
X472639Y-341567D01*
Y-341733D01*
X472512Y-341817D01*
G01X477295Y-345567D02*
X476662Y-344733D01*
X476345Y-343900D01*
Y-340567D01*
X476662Y-339733D01*
X477295Y-338900D01*
G01X482712D02*
X482205Y-339067D01*
X481825Y-339483D01*
X481572Y-339983D01*
X481382Y-340650D01*
X481319Y-341400D01*
X481382Y-342150D01*
X481572Y-342817D01*
X481825Y-343317D01*
X482205Y-343733D01*
X482712Y-343900D01*
X483219Y-343733D01*
X483599Y-343317D01*
X483852Y-342817D01*
X484042Y-342150D01*
X484105Y-341400D01*
X484042Y-340650D01*
X483852Y-339983D01*
X483599Y-339483D01*
X483219Y-339067D01*
X482712Y-338900D01*
G01X486419Y-342900D02*
X486799Y-343483D01*
X487305Y-343817D01*
X487875Y-343900D01*
X488382Y-343817D01*
X488889Y-343400D01*
X489205Y-342900D01*
X489269Y-342400D01*
X489142Y-341817D01*
X488699Y-341400D01*
X488255Y-341233D01*
X487685D01*
G01X488255D02*
X488635Y-340983D01*
X488952Y-340567D01*
X489079Y-340067D01*
X488952Y-339567D01*
X488635Y-339150D01*
X488065Y-338900D01*
X487495Y-338983D01*
X486925Y-339317D01*
G01X493229Y-345567D02*
X493862Y-344733D01*
X494179Y-343900D01*
Y-340567D01*
X493862Y-339733D01*
X493229Y-338900D01*
G01X496619Y-342900D02*
X496999Y-343483D01*
X497505Y-343817D01*
X498075Y-343900D01*
X498582Y-343817D01*
X499089Y-343400D01*
X499405Y-342900D01*
X499469Y-342400D01*
X499342Y-341817D01*
X498899Y-341400D01*
X498455Y-341233D01*
X497885D01*
G01X498455D02*
X498835Y-340983D01*
X499152Y-340567D01*
X499279Y-340067D01*
X499152Y-339567D01*
X498835Y-339150D01*
X498265Y-338900D01*
X497695Y-338983D01*
X497125Y-339317D01*
G01X501909Y-339733D02*
X502289Y-339233D01*
X502732Y-338983D01*
X503239Y-338900D01*
X503872Y-339067D01*
X504315Y-339483D01*
X504442Y-339983D01*
X504379Y-340483D01*
X504125Y-340900D01*
X502859Y-341733D01*
X502289Y-342317D01*
X501909Y-343150D01*
X501782Y-343900D01*
X504442D01*
G01X508085D02*
X508212Y-342817D01*
X508402Y-341900D01*
X508655Y-341067D01*
X508972Y-340150D01*
X509479Y-338900D01*
X506945D01*
G01X512489Y-342233D02*
X514135D01*
G01X517209Y-339733D02*
X517589Y-339233D01*
X518032Y-338983D01*
X518539Y-338900D01*
X519172Y-339067D01*
X519615Y-339483D01*
X519742Y-339983D01*
X519679Y-340483D01*
X519425Y-340900D01*
X518159Y-341733D01*
X517589Y-342317D01*
X517209Y-343150D01*
X517082Y-343900D01*
X519742D01*
G01X522119Y-342900D02*
X522499Y-343483D01*
X523005Y-343817D01*
X523575Y-343900D01*
X524082Y-343817D01*
X524589Y-343400D01*
X524905Y-342900D01*
X524969Y-342400D01*
X524842Y-341817D01*
X524399Y-341400D01*
X523955Y-341233D01*
X523385D01*
G01X523955D02*
X524335Y-340983D01*
X524652Y-340567D01*
X524779Y-340067D01*
X524652Y-339567D01*
X524335Y-339150D01*
X523765Y-338900D01*
X523195Y-338983D01*
X522625Y-339317D01*
G01X529372Y-343900D02*
Y-338900D01*
X527029Y-342483D01*
X530195D01*
G01X532319Y-343150D02*
X532699Y-343567D01*
X533142Y-343817D01*
X533712Y-343900D01*
X534282Y-343733D01*
X534725Y-343400D01*
X535042Y-342817D01*
X535105Y-342150D01*
X534979Y-341483D01*
X534662Y-341067D01*
X534219Y-340733D01*
X533775Y-340650D01*
X533332Y-340733D01*
X532762Y-341067D01*
X532952Y-338900D01*
X534662D01*
G01X542709Y-343900D02*
Y-338900D01*
X545115D01*
G01X544229Y-341317D02*
X542709D01*
G01X547429Y-343900D02*
X549012Y-338900D01*
X550595Y-343900D01*
G01X550025Y-342150D02*
X547999D01*
G01X552782Y-343900D02*
X555442Y-338900D01*
G01X552782D02*
X555442Y-343900D01*
G01X559212Y-344067D02*
X559085Y-343983D01*
Y-343817D01*
X559212Y-343733D01*
X559339Y-343817D01*
Y-343983D01*
X559212Y-344067D01*
G01Y-341817D02*
X559085Y-341733D01*
Y-341567D01*
X559212Y-341483D01*
X559339Y-341567D01*
Y-341733D01*
X559212Y-341817D01*
G01X563995Y-345567D02*
X563362Y-344733D01*
X563045Y-343900D01*
Y-340567D01*
X563362Y-339733D01*
X563995Y-338900D01*
G01X569412D02*
X568905Y-339067D01*
X568525Y-339483D01*
X568272Y-339983D01*
X568082Y-340650D01*
X568019Y-341400D01*
X568082Y-342150D01*
X568272Y-342817D01*
X568525Y-343317D01*
X568905Y-343733D01*
X569412Y-343900D01*
X569919Y-343733D01*
X570299Y-343317D01*
X570552Y-342817D01*
X570742Y-342150D01*
X570805Y-341400D01*
X570742Y-340650D01*
X570552Y-339983D01*
X570299Y-339483D01*
X569919Y-339067D01*
X569412Y-338900D01*
G01X573119Y-342900D02*
X573499Y-343483D01*
X574005Y-343817D01*
X574575Y-343900D01*
X575082Y-343817D01*
X575589Y-343400D01*
X575905Y-342900D01*
X575969Y-342400D01*
X575842Y-341817D01*
X575399Y-341400D01*
X574955Y-341233D01*
X574385D01*
G01X574955D02*
X575335Y-340983D01*
X575652Y-340567D01*
X575779Y-340067D01*
X575652Y-339567D01*
X575335Y-339150D01*
X574765Y-338900D01*
X574195Y-338983D01*
X573625Y-339317D01*
G01X579929Y-345567D02*
X580562Y-344733D01*
X580879Y-343900D01*
Y-340567D01*
X580562Y-339733D01*
X579929Y-338900D01*
G01X583319Y-342900D02*
X583699Y-343483D01*
X584205Y-343817D01*
X584775Y-343900D01*
X585282Y-343817D01*
X585789Y-343400D01*
X586105Y-342900D01*
X586169Y-342400D01*
X586042Y-341817D01*
X585599Y-341400D01*
X585155Y-341233D01*
X584585D01*
G01X585155D02*
X585535Y-340983D01*
X585852Y-340567D01*
X585979Y-340067D01*
X585852Y-339567D01*
X585535Y-339150D01*
X584965Y-338900D01*
X584395Y-338983D01*
X583825Y-339317D01*
G01X588735Y-343317D02*
X589179Y-343733D01*
X589685Y-343900D01*
X590192Y-343733D01*
X590635Y-343233D01*
X590952Y-342483D01*
X591079Y-341733D01*
Y-340817D01*
X590952Y-340067D01*
X590635Y-339400D01*
X590255Y-339067D01*
X589812Y-338900D01*
X589305Y-339067D01*
X588925Y-339400D01*
X588672Y-339900D01*
X588545Y-340567D01*
X588672Y-341150D01*
X588989Y-341733D01*
X589369Y-342067D01*
X589812Y-342150D01*
X590319Y-341983D01*
X590699Y-341567D01*
X591079Y-340817D01*
G01X594785Y-343900D02*
X594912Y-342817D01*
X595102Y-341900D01*
X595355Y-341067D01*
X595672Y-340150D01*
X596179Y-338900D01*
X593645D01*
G01X599189Y-342233D02*
X600835D01*
G01X603719Y-342900D02*
X604099Y-343483D01*
X604605Y-343817D01*
X605175Y-343900D01*
X605682Y-343817D01*
X606189Y-343400D01*
X606505Y-342900D01*
X606569Y-342400D01*
X606442Y-341817D01*
X605999Y-341400D01*
X605555Y-341233D01*
X604985D01*
G01X605555D02*
X605935Y-340983D01*
X606252Y-340567D01*
X606379Y-340067D01*
X606252Y-339567D01*
X605935Y-339150D01*
X605365Y-338900D01*
X604795Y-338983D01*
X604225Y-339317D01*
G01X609009Y-341817D02*
X609452Y-341233D01*
X609832Y-340900D01*
X610339Y-340733D01*
X610782Y-340900D01*
X611099Y-341233D01*
X611352Y-341733D01*
X611415Y-342317D01*
X611352Y-342817D01*
X611099Y-343317D01*
X610719Y-343733D01*
X610275Y-343900D01*
X609769Y-343733D01*
X609325Y-343233D01*
X609072Y-342483D01*
X609009Y-341650D01*
X609135Y-340567D01*
X609325Y-339983D01*
X609642Y-339400D01*
X610085Y-338983D01*
X610529Y-338900D01*
X610972Y-339067D01*
X611289Y-339483D01*
G01X615312Y-343900D02*
Y-338900D01*
X614552Y-339900D01*
G01Y-343900D02*
X616072D01*
G01X621172D02*
Y-338900D01*
X618829Y-342483D01*
X621995D01*
G01X445212Y-273900D02*
Y-348900D01*
X945212D01*
Y-273900D01*
X445212D01*
G01X640212D02*
Y-348900D01*
G01Y-323900D02*
X743212D01*
Y-298900D01*
G01X640212D02*
X743212D01*
G01Y-273900D02*
Y-348900D01*
G01X745212Y-273900D02*
Y-348900D01*
G01X750719Y-333900D02*
Y-328900D01*
X751985D01*
X752492Y-329150D01*
X752872Y-329483D01*
X753189Y-329983D01*
X753442Y-330567D01*
X753505Y-331400D01*
X753442Y-332233D01*
X753189Y-332817D01*
X752872Y-333317D01*
X752492Y-333650D01*
X751985Y-333900D01*
X750719D01*
G01X755629D02*
X757212Y-328900D01*
X758795Y-333900D01*
G01X758225Y-332150D02*
X756199D01*
G01X762312Y-328900D02*
Y-333900D01*
G01X760855Y-328900D02*
X763769D01*
G01X768679Y-333900D02*
X766145D01*
Y-328900D01*
X768679D01*
G01X767665Y-331317D02*
X766145D01*
G01X772512Y-334067D02*
X772385Y-333983D01*
Y-333817D01*
X772512Y-333733D01*
X772639Y-333817D01*
Y-333983D01*
X772512Y-334067D01*
G01Y-331817D02*
X772385Y-331733D01*
Y-331567D01*
X772512Y-331483D01*
X772639Y-331567D01*
Y-331733D01*
X772512Y-331817D01*
G01X745212Y-323900D02*
X945212D01*
G01X750845Y-308900D02*
Y-303900D01*
X752365D01*
X752872Y-304150D01*
X753252Y-304733D01*
X753379Y-305400D01*
X753252Y-306067D01*
X752935Y-306567D01*
X752365Y-306817D01*
X750845D01*
G01X756072Y-309067D02*
X758352Y-303900D01*
G01X760855Y-308900D02*
Y-303900D01*
X763769Y-308900D01*
Y-303900D01*
G01X767412Y-309067D02*
X767285Y-308983D01*
Y-308817D01*
X767412Y-308733D01*
X767539Y-308817D01*
Y-308983D01*
X767412Y-309067D01*
G01Y-306817D02*
X767285Y-306733D01*
Y-306567D01*
X767412Y-306483D01*
X767539Y-306567D01*
Y-306733D01*
X767412Y-306817D01*
G01X745212Y-298900D02*
X945212D01*
G01X750845Y-283900D02*
Y-278900D01*
X752365D01*
X752872Y-279150D01*
X753252Y-279733D01*
X753379Y-280400D01*
X753252Y-281067D01*
X752935Y-281567D01*
X752365Y-281817D01*
X750845D01*
G01X755945Y-283900D02*
Y-278900D01*
X757529D01*
X758035Y-279150D01*
X758352Y-279483D01*
X758479Y-280150D01*
X758352Y-280817D01*
X757972Y-281233D01*
X757529Y-281483D01*
X755945D01*
G01X757529D02*
X758479Y-283900D01*
G01X762312D02*
X761805Y-283817D01*
X761362Y-283483D01*
X760982Y-282983D01*
X760729Y-282400D01*
X760602Y-281733D01*
Y-281067D01*
X760729Y-280400D01*
X760982Y-279817D01*
X761362Y-279317D01*
X761805Y-278983D01*
X762312Y-278900D01*
X762819Y-278983D01*
X763262Y-279317D01*
X763642Y-279817D01*
X763895Y-280400D01*
X764022Y-281067D01*
Y-281733D01*
X763895Y-282400D01*
X763642Y-282983D01*
X763262Y-283483D01*
X762819Y-283817D01*
X762312Y-283900D01*
G01X766145Y-282900D02*
X766462Y-283400D01*
X766842Y-283733D01*
X767285Y-283900D01*
X767792Y-283733D01*
X768172Y-283400D01*
X768552Y-282900D01*
X768679Y-282233D01*
Y-278900D01*
G01X773779Y-283900D02*
X771245D01*
Y-278900D01*
X773779D01*
G01X772765Y-281317D02*
X771245D01*
G01X779005Y-279317D02*
X778625Y-279067D01*
X778182Y-278900D01*
X777675D01*
X777105Y-279150D01*
X776662Y-279567D01*
X776345Y-280067D01*
X776092Y-280900D01*
X776029Y-281650D01*
X776155Y-282400D01*
X776345Y-282900D01*
X776725Y-283400D01*
X777169Y-283733D01*
X777612Y-283900D01*
X778055D01*
X778499Y-283733D01*
X778879Y-283483D01*
X779195Y-283150D01*
G01X782712Y-278900D02*
Y-283900D01*
G01X781255Y-278900D02*
X784169D01*
G01X787812Y-284067D02*
X787685Y-283983D01*
Y-283817D01*
X787812Y-283733D01*
X787939Y-283817D01*
Y-283983D01*
X787812Y-284067D01*
G01Y-281817D02*
X787685Y-281733D01*
Y-281567D01*
X787812Y-281483D01*
X787939Y-281567D01*
Y-281733D01*
X787812Y-281817D01*
G01X860212Y-323900D02*
Y-348900D01*
G01X865845Y-333900D02*
Y-328900D01*
X867429D01*
X867935Y-329150D01*
X868252Y-329483D01*
X868379Y-330150D01*
X868252Y-330817D01*
X867872Y-331233D01*
X867429Y-331483D01*
X865845D01*
G01X867429D02*
X868379Y-333900D01*
G01X873479D02*
X870945D01*
Y-328900D01*
X873479D01*
G01X872465Y-331317D02*
X870945D01*
G01X875729Y-328900D02*
X877312Y-333900D01*
X878895Y-328900D01*
G01X882412Y-334067D02*
X882285Y-333983D01*
Y-333817D01*
X882412Y-333733D01*
X882539Y-333817D01*
Y-333983D01*
X882412Y-334067D01*
G01Y-331817D02*
X882285Y-331733D01*
Y-331567D01*
X882412Y-331483D01*
X882539Y-331567D01*
Y-331733D01*
X882412Y-331817D01*
G01X909212Y-323900D02*
Y-348900D01*
G01X-471400Y-391900D02*
Y1528800D01*
X2244200D01*
Y-391900D01*
X-471400D01*
G01X455917Y-335560D02*
X456544Y-336085D01*
X457249Y-336400D01*
X457875D01*
X458502Y-336085D01*
X458972Y-335560D01*
X459207Y-334825D01*
X459050Y-334090D01*
X458659Y-333460D01*
X457954Y-333040D01*
X457014Y-332830D01*
X456465Y-332410D01*
X456230Y-331675D01*
X456387Y-330940D01*
X456779Y-330415D01*
X457327Y-330100D01*
X457875D01*
X458424Y-330310D01*
X458894Y-330835D01*
G01X462217Y-336400D02*
Y-330100D01*
G01X465507D02*
Y-336400D01*
G01Y-333250D02*
X462217D01*
G01X469222Y-330100D02*
X471102D01*
G01X470162D02*
Y-336400D01*
G01X469222D02*
X471102D01*
G01X478029D02*
X474895D01*
Y-330100D01*
X478029D01*
G01X476775Y-333145D02*
X474895D01*
G01X480960Y-336400D02*
Y-330100D01*
X484564Y-336400D01*
Y-330100D01*
G01X488905Y-337555D02*
X489219Y-336190D01*
G01X495362Y-330100D02*
Y-336400D01*
G01X493560Y-330100D02*
X497164D01*
G01X499704Y-336400D02*
X501662Y-330100D01*
X503620Y-336400D01*
G01X502915Y-334195D02*
X500409D01*
G01X507022Y-330100D02*
X508902D01*
G01X507962D02*
Y-336400D01*
G01X507022D02*
X508902D01*
G01X511912Y-330100D02*
X513009Y-336400D01*
X514262Y-330100D01*
X515515Y-336400D01*
X516612Y-330100D01*
G01X518604Y-336400D02*
X520562Y-330100D01*
X522520Y-336400D01*
G01X521815Y-334195D02*
X519309D01*
G01X525060Y-336400D02*
Y-330100D01*
X528664Y-336400D01*
Y-330100D01*
G01X537895Y-336400D02*
Y-330100D01*
X539854D01*
X540480Y-330415D01*
X540872Y-330835D01*
X541029Y-331675D01*
X540872Y-332515D01*
X540402Y-333040D01*
X539854Y-333355D01*
X537895D01*
G01X539854D02*
X541029Y-336400D01*
G01X545762Y-336610D02*
X545605Y-336505D01*
Y-336295D01*
X545762Y-336190D01*
X545919Y-336295D01*
Y-336505D01*
X545762Y-336610D01*
G01X552062Y-336400D02*
X551435Y-336295D01*
X550887Y-335875D01*
X550417Y-335245D01*
X550104Y-334510D01*
X549947Y-333670D01*
Y-332830D01*
X550104Y-331990D01*
X550417Y-331255D01*
X550887Y-330625D01*
X551435Y-330205D01*
X552062Y-330100D01*
X552689Y-330205D01*
X553237Y-330625D01*
X553707Y-331255D01*
X554020Y-331990D01*
X554177Y-332830D01*
Y-333670D01*
X554020Y-334510D01*
X553707Y-335245D01*
X553237Y-335875D01*
X552689Y-336295D01*
X552062Y-336400D01*
G01X558362Y-336610D02*
X558205Y-336505D01*
Y-336295D01*
X558362Y-336190D01*
X558519Y-336295D01*
Y-336505D01*
X558362Y-336610D01*
G01X566385Y-330625D02*
X565915Y-330310D01*
X565367Y-330100D01*
X564740D01*
X564035Y-330415D01*
X563487Y-330940D01*
X563095Y-331570D01*
X562782Y-332620D01*
X562704Y-333565D01*
X562860Y-334510D01*
X563095Y-335140D01*
X563565Y-335770D01*
X564114Y-336190D01*
X564662Y-336400D01*
X565210D01*
X565759Y-336190D01*
X566229Y-335875D01*
X566620Y-335455D01*
G01X570962Y-336610D02*
X570805Y-336505D01*
Y-336295D01*
X570962Y-336190D01*
X571119Y-336295D01*
Y-336505D01*
X570962Y-336610D01*
G01X455839Y-326400D02*
Y-320100D01*
G01X458815D02*
X455839Y-323985D01*
G01X459285Y-326400D02*
X457170Y-322200D01*
G01X462139Y-320100D02*
Y-324615D01*
X462452Y-325560D01*
X463079Y-326190D01*
X463862Y-326400D01*
X464645Y-326190D01*
X465272Y-325560D01*
X465585Y-324615D01*
Y-320100D01*
G01X471729Y-326400D02*
X468595D01*
Y-320100D01*
X471729D01*
G01X470475Y-323145D02*
X468595D01*
G01X475522Y-320100D02*
X477402D01*
G01X476462D02*
Y-326400D01*
G01X475522D02*
X477402D01*
G01X487417Y-325560D02*
X488044Y-326085D01*
X488749Y-326400D01*
X489375D01*
X490002Y-326085D01*
X490472Y-325560D01*
X490707Y-324825D01*
X490550Y-324090D01*
X490159Y-323460D01*
X489454Y-323040D01*
X488514Y-322830D01*
X487965Y-322410D01*
X487730Y-321675D01*
X487887Y-320940D01*
X488279Y-320415D01*
X488827Y-320100D01*
X489375D01*
X489924Y-320310D01*
X490394Y-320835D01*
G01X493717Y-326400D02*
Y-320100D01*
G01X497007D02*
Y-326400D01*
G01Y-323250D02*
X493717D01*
G01X499704Y-326400D02*
X501662Y-320100D01*
X503620Y-326400D01*
G01X502915Y-324195D02*
X500409D01*
G01X506160Y-326400D02*
Y-320100D01*
X509764Y-326400D01*
Y-320100D01*
G01X518917Y-326400D02*
Y-320100D01*
G01X522207D02*
Y-326400D01*
G01Y-323250D02*
X518917D01*
G01X525217Y-325560D02*
X525844Y-326085D01*
X526549Y-326400D01*
X527175D01*
X527802Y-326085D01*
X528272Y-325560D01*
X528507Y-324825D01*
X528350Y-324090D01*
X527959Y-323460D01*
X527254Y-323040D01*
X526314Y-322830D01*
X525765Y-322410D01*
X525530Y-321675D01*
X525687Y-320940D01*
X526079Y-320415D01*
X526627Y-320100D01*
X527175D01*
X527724Y-320310D01*
X528194Y-320835D01*
G01X532222Y-320100D02*
X534102D01*
G01X533162D02*
Y-326400D01*
G01X532222D02*
X534102D01*
G01X537504D02*
X539462Y-320100D01*
X541420Y-326400D01*
G01X540715Y-324195D02*
X538209D01*
G01X543960Y-326400D02*
Y-320100D01*
X547564Y-326400D01*
Y-320100D01*
G01X552532Y-323250D02*
X554099D01*
Y-325140D01*
X553629Y-325770D01*
X553080Y-326190D01*
X552297Y-326400D01*
X551514Y-326190D01*
X550965Y-325770D01*
X550495Y-325140D01*
X550182Y-324405D01*
X550025Y-323565D01*
Y-322830D01*
X550182Y-322200D01*
X550495Y-321465D01*
X550965Y-320835D01*
X551435Y-320415D01*
X552062Y-320100D01*
X552610D01*
X553237Y-320310D01*
X553707Y-320730D01*
G01X558205Y-327555D02*
X558519Y-326190D01*
G01X564662Y-320100D02*
Y-326400D01*
G01X562860Y-320100D02*
X566464D01*
G01X569004Y-326400D02*
X570962Y-320100D01*
X572920Y-326400D01*
G01X572215Y-324195D02*
X569709D01*
G01X577262Y-326400D02*
X576635Y-326295D01*
X576087Y-325875D01*
X575617Y-325245D01*
X575304Y-324510D01*
X575147Y-323670D01*
Y-322830D01*
X575304Y-321990D01*
X575617Y-321255D01*
X576087Y-320625D01*
X576635Y-320205D01*
X577262Y-320100D01*
X577889Y-320205D01*
X578437Y-320625D01*
X578907Y-321255D01*
X579220Y-321990D01*
X579377Y-322830D01*
Y-323670D01*
X579220Y-324510D01*
X578907Y-325245D01*
X578437Y-325875D01*
X577889Y-326295D01*
X577262Y-326400D01*
G01X589862D02*
Y-323565D01*
X588295Y-320100D01*
G01X591429D02*
X589862Y-323565D01*
G01X594439Y-320100D02*
Y-324615D01*
X594752Y-325560D01*
X595379Y-326190D01*
X596162Y-326400D01*
X596945Y-326190D01*
X597572Y-325560D01*
X597885Y-324615D01*
Y-320100D01*
G01X600504Y-326400D02*
X602462Y-320100D01*
X604420Y-326400D01*
G01X603715Y-324195D02*
X601209D01*
G01X606960Y-326400D02*
Y-320100D01*
X610564Y-326400D01*
Y-320100D01*
G01X455760Y-316400D02*
Y-310100D01*
X459364Y-316400D01*
Y-310100D01*
G01X463862Y-316400D02*
X463235Y-316295D01*
X462687Y-315875D01*
X462217Y-315245D01*
X461904Y-314510D01*
X461747Y-313670D01*
Y-312830D01*
X461904Y-311990D01*
X462217Y-311255D01*
X462687Y-310625D01*
X463235Y-310205D01*
X463862Y-310100D01*
X464489Y-310205D01*
X465037Y-310625D01*
X465507Y-311255D01*
X465820Y-311990D01*
X465977Y-312830D01*
Y-313670D01*
X465820Y-314510D01*
X465507Y-315245D01*
X465037Y-315875D01*
X464489Y-316295D01*
X463862Y-316400D01*
G01X470162Y-316610D02*
X470005Y-316505D01*
Y-316295D01*
X470162Y-316190D01*
X470319Y-316295D01*
Y-316505D01*
X470162Y-316610D01*
G01X476462Y-316400D02*
Y-310100D01*
X475522Y-311360D01*
G01Y-316400D02*
X477402D01*
G01X482762D02*
X483310Y-316295D01*
X483937Y-315980D01*
X484329Y-315455D01*
X484485Y-314720D01*
X484329Y-313985D01*
X483859Y-313355D01*
X483154Y-313040D01*
X482370D01*
X481900Y-312830D01*
X481509Y-312305D01*
X481352Y-311570D01*
X481587Y-310835D01*
X482135Y-310310D01*
X482762Y-310100D01*
X483389Y-310310D01*
X483937Y-310835D01*
X484172Y-311570D01*
X484015Y-312305D01*
X483624Y-312830D01*
X483154Y-313040D01*
X482370D01*
X481665Y-313355D01*
X481195Y-313985D01*
X481039Y-314720D01*
X481195Y-315455D01*
X481587Y-315980D01*
X482214Y-316295D01*
X482762Y-316400D01*
G01X489062D02*
X489610Y-316295D01*
X490237Y-315980D01*
X490629Y-315455D01*
X490785Y-314720D01*
X490629Y-313985D01*
X490159Y-313355D01*
X489454Y-313040D01*
X488670D01*
X488200Y-312830D01*
X487809Y-312305D01*
X487652Y-311570D01*
X487887Y-310835D01*
X488435Y-310310D01*
X489062Y-310100D01*
X489689Y-310310D01*
X490237Y-310835D01*
X490472Y-311570D01*
X490315Y-312305D01*
X489924Y-312830D01*
X489454Y-313040D01*
X488670D01*
X487965Y-313355D01*
X487495Y-313985D01*
X487339Y-314720D01*
X487495Y-315455D01*
X487887Y-315980D01*
X488514Y-316295D01*
X489062Y-316400D01*
G01X495205Y-317555D02*
X495519Y-316190D01*
G01X499312Y-310100D02*
X500409Y-316400D01*
X501662Y-310100D01*
X502915Y-316400D01*
X504012Y-310100D01*
G01X509529Y-316400D02*
X506395D01*
Y-310100D01*
X509529D01*
G01X508275Y-313145D02*
X506395D01*
G01X512460Y-316400D02*
Y-310100D01*
X516064Y-316400D01*
Y-310100D01*
G01X525217Y-316400D02*
Y-310100D01*
G01X528507D02*
Y-316400D01*
G01Y-313250D02*
X525217D01*
G01X530812Y-310100D02*
X531909Y-316400D01*
X533162Y-310100D01*
X534415Y-316400D01*
X535512Y-310100D01*
G01X537504Y-316400D02*
X539462Y-310100D01*
X541420Y-316400D01*
G01X540715Y-314195D02*
X538209D01*
G01X550574Y-311150D02*
X551044Y-310520D01*
X551592Y-310205D01*
X552219Y-310100D01*
X553002Y-310310D01*
X553550Y-310835D01*
X553707Y-311465D01*
X553629Y-312095D01*
X553315Y-312620D01*
X551749Y-313670D01*
X551044Y-314405D01*
X550574Y-315455D01*
X550417Y-316400D01*
X553707D01*
G01X556560D02*
Y-310100D01*
X560164Y-316400D01*
Y-310100D01*
G01X562939Y-316400D02*
Y-310100D01*
X564505D01*
X565132Y-310415D01*
X565602Y-310835D01*
X565994Y-311465D01*
X566307Y-312200D01*
X566385Y-313250D01*
X566307Y-314300D01*
X565994Y-315035D01*
X565602Y-315665D01*
X565132Y-316085D01*
X564505Y-316400D01*
X562939D01*
G01X575695D02*
Y-310100D01*
X577654D01*
X578280Y-310415D01*
X578672Y-310835D01*
X578829Y-311675D01*
X578672Y-312515D01*
X578202Y-313040D01*
X577654Y-313355D01*
X575695D01*
G01X577654D02*
X578829Y-316400D01*
G01X581839D02*
Y-310100D01*
X583405D01*
X584032Y-310415D01*
X584502Y-310835D01*
X584894Y-311465D01*
X585207Y-312200D01*
X585285Y-313250D01*
X585207Y-314300D01*
X584894Y-315035D01*
X584502Y-315665D01*
X584032Y-316085D01*
X583405Y-316400D01*
X581839D01*
G01X589862Y-316610D02*
X589705Y-316505D01*
Y-316295D01*
X589862Y-316190D01*
X590019Y-316295D01*
Y-316505D01*
X589862Y-316610D01*
G01X479862Y-303700D02*
X477342Y-303283D01*
X475137Y-301617D01*
X473247Y-299117D01*
X471987Y-296200D01*
X471357Y-292867D01*
Y-289533D01*
X471987Y-286200D01*
X473247Y-283283D01*
X475137Y-280784D01*
X477342Y-279117D01*
X479862Y-278700D01*
X482382Y-279117D01*
X484587Y-280784D01*
X486477Y-283283D01*
X487737Y-286200D01*
X488367Y-289533D01*
Y-292867D01*
X487737Y-296200D01*
X486477Y-299117D01*
X484587Y-301617D01*
X482382Y-303283D01*
X479862Y-303700D01*
G01X482382Y-297033D02*
X486162Y-303700D01*
G01X499707Y-287034D02*
Y-298700D01*
X500967Y-301617D01*
X502857Y-303283D01*
X505062Y-303700D01*
X507267Y-303283D01*
X509157Y-301617D01*
X510417Y-298700D01*
G01Y-303700D02*
Y-287034D01*
G01X535932Y-303700D02*
Y-287034D01*
G01Y-289950D02*
X534672Y-288284D01*
X532782Y-287450D01*
X530577Y-287034D01*
X528372Y-287867D01*
X526482Y-289533D01*
X525222Y-292034D01*
X524592Y-295367D01*
X525222Y-298700D01*
X526482Y-301201D01*
X528372Y-302867D01*
X530577Y-303700D01*
X532782Y-303283D01*
X534672Y-302034D01*
X535932Y-300367D01*
G01X550107Y-303700D02*
Y-287034D01*
G01Y-291200D02*
X551367Y-289117D01*
X553257Y-287450D01*
X555777Y-287034D01*
X557982Y-287450D01*
X559872Y-289117D01*
X560817Y-292034D01*
Y-303700D01*
G01X580662Y-278700D02*
Y-303700D01*
G01X576252Y-287034D02*
X585072D01*
G01X611532Y-303700D02*
Y-287034D01*
G01Y-289950D02*
X610272Y-288284D01*
X608382Y-287450D01*
X606177Y-287034D01*
X603972Y-287867D01*
X602082Y-289533D01*
X600822Y-292034D01*
X600192Y-295367D01*
X600822Y-298700D01*
X602082Y-301201D01*
X603972Y-302867D01*
X606177Y-303700D01*
X608382Y-303283D01*
X610272Y-302034D01*
X611532Y-300367D01*
G01X651212Y-283400D02*
Y-291400D01*
X655212D01*
G01X663012D02*
Y-286067D01*
G01Y-287000D02*
X662612Y-286467D01*
X662012Y-286200D01*
X661312Y-286067D01*
X660612Y-286333D01*
X660012Y-286867D01*
X659612Y-287667D01*
X659412Y-288733D01*
X659612Y-289800D01*
X660012Y-290600D01*
X660612Y-291133D01*
X661312Y-291400D01*
X662012Y-291267D01*
X662612Y-290867D01*
X663012Y-290334D01*
G01X667112Y-293800D02*
X667712Y-294067D01*
X668512Y-293800D01*
X669012Y-293267D01*
X669412Y-292600D01*
X670012Y-290467D01*
X671312Y-286067D01*
G01X668112D02*
X670012Y-290467D01*
G01X675712Y-287800D02*
X678912D01*
X678612Y-286867D01*
X678112Y-286333D01*
X677412Y-286067D01*
X676712Y-286200D01*
X676112Y-286600D01*
X675712Y-287533D01*
X675512Y-288334D01*
Y-289133D01*
X675712Y-289933D01*
X676212Y-290733D01*
X676812Y-291267D01*
X677512Y-291400D01*
X678212Y-291133D01*
X678912Y-290334D01*
G01X683812Y-291400D02*
Y-286067D01*
G01Y-287133D02*
X684312Y-286600D01*
X684812Y-286200D01*
X685512Y-286067D01*
X686012Y-286200D01*
X686612Y-286600D01*
G01X673512Y-333400D02*
X675912D01*
G01X674712D02*
Y-341400D01*
G01X673512D02*
X675912D01*
G01X681312D02*
Y-336067D01*
G01Y-337133D02*
X681812Y-336600D01*
X682312Y-336200D01*
X683012Y-336067D01*
X683512Y-336200D01*
X684112Y-336600D01*
G01X689212Y-337800D02*
X692412D01*
X692112Y-336867D01*
X691612Y-336333D01*
X690912Y-336067D01*
X690212Y-336200D01*
X689612Y-336600D01*
X689212Y-337533D01*
X689012Y-338334D01*
Y-339133D01*
X689212Y-339933D01*
X689712Y-340733D01*
X690312Y-341267D01*
X691012Y-341400D01*
X691712Y-341133D01*
X692412Y-340334D01*
G01X697012Y-341400D02*
Y-336067D01*
G01Y-337400D02*
X697412Y-336733D01*
X698012Y-336200D01*
X698812Y-336067D01*
X699512Y-336200D01*
X700112Y-336733D01*
X700412Y-337667D01*
Y-341400D01*
G01X705212Y-337800D02*
X708412D01*
X708112Y-336867D01*
X707612Y-336333D01*
X706912Y-336067D01*
X706212Y-336200D01*
X705612Y-336600D01*
X705212Y-337533D01*
X705012Y-338334D01*
Y-339133D01*
X705212Y-339933D01*
X705712Y-340733D01*
X706312Y-341267D01*
X707012Y-341400D01*
X707712Y-341133D01*
X708412Y-340334D01*
G01X680312Y-312400D02*
X682312D01*
Y-314800D01*
X681712Y-315600D01*
X681012Y-316133D01*
X680012Y-316400D01*
X679012Y-316133D01*
X678312Y-315600D01*
X677712Y-314800D01*
X677312Y-313867D01*
X677112Y-312800D01*
Y-311867D01*
X677312Y-311067D01*
X677712Y-310133D01*
X678312Y-309333D01*
X678912Y-308800D01*
X679712Y-308400D01*
X680412D01*
X681212Y-308667D01*
X681812Y-309200D01*
G01X685412Y-316400D02*
Y-308400D01*
X690012Y-316400D01*
Y-308400D01*
G01X693512Y-316400D02*
Y-308400D01*
X695512D01*
X696312Y-308800D01*
X696912Y-309333D01*
X697412Y-310133D01*
X697812Y-311067D01*
X697912Y-312400D01*
X697812Y-313733D01*
X697412Y-314667D01*
X696912Y-315467D01*
X696312Y-316000D01*
X695512Y-316400D01*
X693512D01*
G01X702812Y-284733D02*
X703412Y-283933D01*
X704112Y-283533D01*
X704912Y-283400D01*
X705912Y-283667D01*
X706612Y-284333D01*
X706812Y-285133D01*
X706712Y-285934D01*
X706312Y-286600D01*
X704312Y-287933D01*
X703412Y-288867D01*
X702812Y-290200D01*
X702612Y-291400D01*
X706812D01*
G01X777812Y-334733D02*
X778412Y-333933D01*
X779112Y-333533D01*
X779912Y-333400D01*
X780912Y-333667D01*
X781612Y-334333D01*
X781812Y-335133D01*
X781712Y-335934D01*
X781312Y-336600D01*
X779312Y-337933D01*
X778412Y-338867D01*
X777812Y-340200D01*
X777612Y-341400D01*
X781812D01*
G01X787712Y-333400D02*
X786912Y-333667D01*
X786312Y-334333D01*
X785912Y-335133D01*
X785612Y-336200D01*
X785512Y-337400D01*
X785612Y-338600D01*
X785912Y-339667D01*
X786312Y-340467D01*
X786912Y-341133D01*
X787712Y-341400D01*
X788512Y-341133D01*
X789112Y-340467D01*
X789512Y-339667D01*
X789812Y-338600D01*
X789912Y-337400D01*
X789812Y-336200D01*
X789512Y-335133D01*
X789112Y-334333D01*
X788512Y-333667D01*
X787712Y-333400D01*
G01X795712Y-341400D02*
Y-333400D01*
X794512Y-335000D01*
G01Y-341400D02*
X796912D01*
G01X801812Y-334733D02*
X802412Y-333933D01*
X803112Y-333533D01*
X803912Y-333400D01*
X804912Y-333667D01*
X805612Y-334333D01*
X805812Y-335133D01*
X805712Y-335934D01*
X805312Y-336600D01*
X803312Y-337933D01*
X802412Y-338867D01*
X801812Y-340200D01*
X801612Y-341400D01*
X805812D01*
G01X809912Y-341667D02*
X813512Y-333400D01*
G01X819712Y-341400D02*
Y-333400D01*
X818512Y-335000D01*
G01Y-341400D02*
X820912D01*
G01X827712Y-333400D02*
X826912Y-333667D01*
X826312Y-334333D01*
X825912Y-335133D01*
X825612Y-336200D01*
X825512Y-337400D01*
X825612Y-338600D01*
X825912Y-339667D01*
X826312Y-340467D01*
X826912Y-341133D01*
X827712Y-341400D01*
X828512Y-341133D01*
X829112Y-340467D01*
X829512Y-339667D01*
X829812Y-338600D01*
X829912Y-337400D01*
X829812Y-336200D01*
X829512Y-335133D01*
X829112Y-334333D01*
X828512Y-333667D01*
X827712Y-333400D01*
G01X833912Y-341667D02*
X837512Y-333400D01*
G01X841512Y-339800D02*
X842112Y-340733D01*
X842912Y-341267D01*
X843812Y-341400D01*
X844612Y-341267D01*
X845412Y-340600D01*
X845912Y-339800D01*
X846012Y-339000D01*
X845812Y-338067D01*
X845112Y-337400D01*
X844412Y-337133D01*
X843512D01*
G01X844412D02*
X845012Y-336733D01*
X845512Y-336067D01*
X845712Y-335267D01*
X845512Y-334467D01*
X845012Y-333800D01*
X844112Y-333400D01*
X843212Y-333533D01*
X842312Y-334067D01*
G01X851712Y-341400D02*
Y-333400D01*
X850512Y-335000D01*
G01Y-341400D02*
X852912D01*
G01X777512Y-316400D02*
Y-308400D01*
X779512D01*
X780312Y-308800D01*
X780912Y-309333D01*
X781412Y-310133D01*
X781812Y-311067D01*
X781912Y-312400D01*
X781812Y-313733D01*
X781412Y-314667D01*
X780912Y-315467D01*
X780312Y-316000D01*
X779512Y-316400D01*
X777512D01*
G01X785212D02*
X787712Y-308400D01*
X790212Y-316400D01*
G01X789312Y-313600D02*
X786112D01*
G01X795712Y-308400D02*
X794912Y-308667D01*
X794312Y-309333D01*
X793912Y-310133D01*
X793612Y-311200D01*
X793512Y-312400D01*
X793612Y-313600D01*
X793912Y-314667D01*
X794312Y-315467D01*
X794912Y-316133D01*
X795712Y-316400D01*
X796512Y-316133D01*
X797112Y-315467D01*
X797512Y-314667D01*
X797812Y-313600D01*
X797912Y-312400D01*
X797812Y-311200D01*
X797512Y-310133D01*
X797112Y-309333D01*
X796512Y-308667D01*
X795712Y-308400D01*
G01X803712D02*
Y-316400D01*
G01X801412Y-308400D02*
X806012D01*
G01X809812Y-313067D02*
X810512Y-312133D01*
X811112Y-311600D01*
X811912Y-311333D01*
X812612Y-311600D01*
X813112Y-312133D01*
X813512Y-312933D01*
X813612Y-313867D01*
X813512Y-314667D01*
X813112Y-315467D01*
X812512Y-316133D01*
X811812Y-316400D01*
X811012Y-316133D01*
X810312Y-315334D01*
X809912Y-314133D01*
X809812Y-312800D01*
X810012Y-311067D01*
X810312Y-310133D01*
X810812Y-309200D01*
X811512Y-308533D01*
X812212Y-308400D01*
X812912Y-308667D01*
X813412Y-309333D01*
G01X817112Y-316400D02*
Y-308400D01*
X819712Y-315067D01*
X822312Y-308400D01*
Y-316400D01*
G01X827712Y-308400D02*
Y-316400D01*
G01X825412Y-308400D02*
X830012D01*
G01X833612Y-316400D02*
Y-308400D01*
G01X837812D02*
Y-316400D01*
G01Y-312400D02*
X833612D01*
G01X843712Y-316400D02*
X844412Y-316267D01*
X845212Y-315867D01*
X845712Y-315200D01*
X845912Y-314267D01*
X845712Y-313334D01*
X845112Y-312533D01*
X844212Y-312133D01*
X843212D01*
X842612Y-311867D01*
X842112Y-311200D01*
X841912Y-310267D01*
X842212Y-309333D01*
X842912Y-308667D01*
X843712Y-308400D01*
X844512Y-308667D01*
X845212Y-309333D01*
X845512Y-310267D01*
X845312Y-311200D01*
X844812Y-311867D01*
X844212Y-312133D01*
X843212D01*
X842312Y-312533D01*
X841712Y-313334D01*
X841512Y-314267D01*
X841712Y-315200D01*
X842212Y-315867D01*
X843012Y-316267D01*
X843712Y-316400D01*
G01X853912Y-309067D02*
X853312Y-308667D01*
X852612Y-308400D01*
X851812D01*
X850912Y-308800D01*
X850212Y-309467D01*
X849712Y-310267D01*
X849312Y-311600D01*
X849212Y-312800D01*
X849412Y-314000D01*
X849712Y-314800D01*
X850312Y-315600D01*
X851012Y-316133D01*
X851712Y-316400D01*
X852412D01*
X853112Y-316133D01*
X853712Y-315733D01*
X854212Y-315200D01*
G01X859712Y-308400D02*
X858912Y-308667D01*
X858312Y-309333D01*
X857912Y-310133D01*
X857612Y-311200D01*
X857512Y-312400D01*
X857612Y-313600D01*
X857912Y-314667D01*
X858312Y-315467D01*
X858912Y-316133D01*
X859712Y-316400D01*
X860512Y-316133D01*
X861112Y-315467D01*
X861512Y-314667D01*
X861812Y-313600D01*
X861912Y-312400D01*
X861812Y-311200D01*
X861512Y-310133D01*
X861112Y-309333D01*
X860512Y-308667D01*
X859712Y-308400D01*
G01X799712Y-283400D02*
Y-291400D01*
G01X797412Y-283400D02*
X802012D01*
G01X805812Y-288067D02*
X806512Y-287133D01*
X807112Y-286600D01*
X807912Y-286333D01*
X808612Y-286600D01*
X809112Y-287133D01*
X809512Y-287933D01*
X809612Y-288867D01*
X809512Y-289667D01*
X809112Y-290467D01*
X808512Y-291133D01*
X807812Y-291400D01*
X807012Y-291133D01*
X806312Y-290334D01*
X805912Y-289133D01*
X805812Y-287800D01*
X806012Y-286067D01*
X806312Y-285133D01*
X806812Y-284200D01*
X807512Y-283533D01*
X808212Y-283400D01*
X808912Y-283667D01*
X809412Y-284333D01*
G01X813112Y-291400D02*
Y-283400D01*
X815712Y-290067D01*
X818312Y-283400D01*
Y-291400D01*
G01X820712Y-294067D02*
X826712D01*
G01X831712Y-283400D02*
Y-291400D01*
G01X829412Y-283400D02*
X834012D01*
G01X838312Y-291400D02*
Y-286067D01*
G01Y-287133D02*
X838812Y-286600D01*
X839312Y-286200D01*
X840012Y-286067D01*
X840512Y-286200D01*
X841112Y-286600D01*
G01X849512Y-291400D02*
Y-286067D01*
G01Y-287000D02*
X849112Y-286467D01*
X848512Y-286200D01*
X847812Y-286067D01*
X847112Y-286333D01*
X846512Y-286867D01*
X846112Y-287667D01*
X845912Y-288733D01*
X846112Y-289800D01*
X846512Y-290600D01*
X847112Y-291133D01*
X847812Y-291400D01*
X848512Y-291267D01*
X849112Y-290867D01*
X849512Y-290334D01*
G01X853612Y-293800D02*
X854212Y-294067D01*
X855012Y-293800D01*
X855512Y-293267D01*
X855912Y-292600D01*
X856512Y-290467D01*
X857812Y-286067D01*
G01X854612D02*
X856512Y-290467D01*
G01X860712Y-294067D02*
X866712D01*
G01X872512Y-287133D02*
X872912Y-286733D01*
X873212Y-286067D01*
X873412Y-285133D01*
X873212Y-284333D01*
X872812Y-283800D01*
X872112Y-283400D01*
X869412D01*
Y-291400D01*
X872712D01*
X873412Y-290867D01*
X873812Y-290067D01*
X874012Y-289133D01*
X873812Y-288200D01*
X873212Y-287400D01*
X872512Y-287133D01*
X869412D01*
G01X877712Y-291400D02*
Y-283400D01*
X880112D01*
X880912Y-283800D01*
X881512Y-284733D01*
X881712Y-285800D01*
X881512Y-286867D01*
X881012Y-287667D01*
X880112Y-288067D01*
X877712D01*
G01X896912Y-334067D02*
X896312Y-333667D01*
X895612Y-333400D01*
X894812D01*
X893912Y-333800D01*
X893212Y-334467D01*
X892712Y-335267D01*
X892312Y-336600D01*
X892212Y-337800D01*
X892412Y-339000D01*
X892712Y-339800D01*
X893312Y-340600D01*
X894012Y-341133D01*
X894712Y-341400D01*
X895412D01*
X896112Y-341133D01*
X896712Y-340733D01*
X897212Y-340200D01*
G01X922212Y-341400D02*
Y-333400D01*
X921012Y-335000D01*
G01Y-341400D02*
X923412D01*
G01X928312Y-338067D02*
X929012Y-337133D01*
X929612Y-336600D01*
X930412Y-336333D01*
X931112Y-336600D01*
X931612Y-337133D01*
X932012Y-337933D01*
X932112Y-338867D01*
X932012Y-339667D01*
X931612Y-340467D01*
X931012Y-341133D01*
X930312Y-341400D01*
X929512Y-341133D01*
X928812Y-340334D01*
X928412Y-339133D01*
X928312Y-337800D01*
X928512Y-336067D01*
X928812Y-335133D01*
X929312Y-334200D01*
X930012Y-333533D01*
X930712Y-333400D01*
X931412Y-333667D01*
X931912Y-334333D01*
M02*
